G04 ================== begin FILE IDENTIFICATION RECORD ==================*
G04 Layout Name:  12433-2a.brd*
G04 Film Name:    L1*
G04 File Format:  Gerber RS274X*
G04 File Origin:  Cadence Allegro 16.5-S056*
G04 Origin Date:  Fri Dec 11 16:47:39 2015*
G04 *
G04 Layer:  VIA CLASS/TOP*
G04 Layer:  PIN/TOP*
G04 Layer:  ETCH/TOP*
G04 Layer:  DRAWING FORMAT/LAYER_PCB_STORY*
G04 Layer:  DRAWING FORMAT/LAYER_L1*
G04 *
G04 Offset:    (0.00 0.00)*
G04 Mirror:    No*
G04 Mode:      Positive*
G04 Rotation:  0*
G04 FullContactRelief:  No*
G04 UndefLineWidth:     6.00*
G04 ================== end FILE IDENTIFICATION RECORD ====================*
%FSLAX35Y35*MOIN*%
%IR0*IPPOS*OFA0.00000B0.00000*MIA0B0*SFA1.00000B1.00000*%
%AMMACRO40*
4,1,40,.013,.017,
-.013,.017,
-.013695,.016939,
-.014368,.016759,
-.015,.016464,
-.015571,.016064,
-.016064,.015571,
-.016464,.015,
-.016759,.014368,
-.016939,.013695,
-.017,.013,
-.017,-.013,
-.016939,-.013695,
-.016759,-.014368,
-.016464,-.015,
-.016064,-.015571,
-.015571,-.016064,
-.015,-.016464,
-.014368,-.016759,
-.013695,-.016939,
-.013,-.017,
.013,-.017,
.013695,-.016939,
.014368,-.016759,
.015,-.016464,
.015571,-.016064,
.016064,-.015571,
.016464,-.015,
.016759,-.014368,
.016939,-.013695,
.017,-.013,
.017,.013,
.016939,.013695,
.016759,.014368,
.016464,.015,
.016064,.015571,
.015571,.016064,
.015,.016464,
.014368,.016759,
.013695,.016939,
.013,.017,
0.0*
%
%ADD40MACRO40*%
%AMMACRO31*
4,1,40,.017,-.013,
.017,.013,
.016939,.013695,
.016759,.014368,
.016464,.015,
.016064,.015571,
.015571,.016064,
.015,.016464,
.014368,.016759,
.013695,.016939,
.013,.017,
-.013,.017,
-.013695,.016939,
-.014368,.016759,
-.015,.016464,
-.015571,.016064,
-.016064,.015571,
-.016464,.015,
-.016759,.014368,
-.016939,.013695,
-.017,.013,
-.017,-.013,
-.016939,-.013695,
-.016759,-.014368,
-.016464,-.015,
-.016064,-.015571,
-.015571,-.016064,
-.015,-.016464,
-.014368,-.016759,
-.013695,-.016939,
-.013,-.017,
.013,-.017,
.013695,-.016939,
.014368,-.016759,
.015,-.016464,
.015571,-.016064,
.016064,-.015571,
.016464,-.015,
.016759,-.014368,
.016939,-.013695,
.017,-.013,
0.0*
%
%ADD31MACRO31*%
%ADD10C,.01*%
%ADD33R,.08X.127*%
%ADD15C,.022*%
%ADD54C,.032*%
%ADD16C,.05*%
%ADD49R,.085X.128*%
%ADD12C,.028*%
%ADD55R,.208X.087*%
%ADD13C,.056*%
%ADD46C,.057*%
%ADD39R,.087X.208*%
%ADD11R,.05X.05*%
%AMMACRO88*
4,1,40,-.014,-.008,
-.014,.008,
-.013939,.008695,
-.013759,.009368,
-.013464,.01,
-.013064,.010571,
-.012571,.011064,
-.012,.011464,
-.011368,.011759,
-.010695,.011939,
-.01,.012,
.01,.012,
.010695,.011939,
.011368,.011759,
.012,.011464,
.012571,.011064,
.013064,.010571,
.013464,.01,
.013759,.009368,
.013939,.008695,
.014,.008,
.014,-.008,
.013939,-.008695,
.013759,-.009368,
.013464,-.01,
.013064,-.010571,
.012571,-.011064,
.012,-.011464,
.011368,-.011759,
.010695,-.011939,
.01,-.012,
-.01,-.012,
-.010695,-.011939,
-.011368,-.011759,
-.012,-.011464,
-.012571,-.011064,
-.013064,-.010571,
-.013464,-.01,
-.013759,-.009368,
-.013939,-.008695,
-.014,-.008,
0.0*
%
%ADD88MACRO88*%
%AMMACRO80*
4,1,40,-.007,-.0225,
-.008389,-.022378,
-.009736,-.022018,
-.011,-.021428,
-.012142,-.020628,
-.013128,-.019642,
-.013928,-.0185,
-.014518,-.017236,
-.014878,-.015889,
-.015,-.0145,
-.015,.0145,
-.014878,.015889,
-.014518,.017236,
-.013928,.0185,
-.013128,.019642,
-.012142,.020628,
-.011,.021428,
-.009736,.022018,
-.008389,.022378,
-.007,.0225,
.007,.0225,
.008389,.022378,
.009736,.022018,
.011,.021428,
.012142,.020628,
.013128,.019642,
.013928,.0185,
.014518,.017236,
.014878,.015889,
.015,.0145,
.015,-.0145,
.014878,-.015889,
.014518,-.017236,
.013928,-.0185,
.013128,-.019642,
.012142,-.020628,
.011,-.021428,
.009736,-.022018,
.008389,-.022378,
.007,-.0225,
-.007,-.0225,
0.0*
%
%ADD80MACRO80*%
%AMMACRO41*
4,1,40,.011,-.007,
.011,.007,
.010939,.007695,
.010759,.008368,
.010464,.009,
.010064,.009571,
.009571,.010064,
.009,.010464,
.008368,.010759,
.007695,.010939,
.007,.011,
-.007,.011,
-.007695,.010939,
-.008368,.010759,
-.009,.010464,
-.009571,.010064,
-.010064,.009571,
-.010464,.009,
-.010759,.008368,
-.010939,.007695,
-.011,.007,
-.011,-.007,
-.010939,-.007695,
-.010759,-.008368,
-.010464,-.009,
-.010064,-.009571,
-.009571,-.010064,
-.009,-.010464,
-.008368,-.010759,
-.007695,-.010939,
-.007,-.011,
.007,-.011,
.007695,-.010939,
.008368,-.010759,
.009,-.010464,
.009571,-.010064,
.010064,-.009571,
.010464,-.009,
.010759,-.008368,
.010939,-.007695,
.011,-.007,
0.0*
%
%ADD41MACRO41*%
%AMMACRO19*
4,1,40,.007,.011,
-.007,.011,
-.007695,.010939,
-.008368,.010759,
-.009,.010464,
-.009571,.010064,
-.010064,.009571,
-.010464,.009,
-.010759,.008368,
-.010939,.007695,
-.011,.007,
-.011,-.007,
-.010939,-.007695,
-.010759,-.008368,
-.010464,-.009,
-.010064,-.009571,
-.009571,-.010064,
-.009,-.010464,
-.008368,-.010759,
-.007695,-.010939,
-.007,-.011,
.007,-.011,
.007695,-.010939,
.008368,-.010759,
.009,-.010464,
.009571,-.010064,
.010064,-.009571,
.010464,-.009,
.010759,-.008368,
.010939,-.007695,
.011,-.007,
.011,.007,
.010939,.007695,
.010759,.008368,
.010464,.009,
.010064,.009571,
.009571,.010064,
.009,.010464,
.008368,.010759,
.007695,.010939,
.007,.011,
0.0*
%
%ADD19MACRO19*%
%AMMACRO85*
4,1,22,.007,.0145,
.007695,.014439,
.008368,.014259,
.009,.013964,
.009571,.013564,
.010064,.013071,
.010464,.0125,
.010759,.011868,
.010939,.011195,
.011,.0105,
.011,-.0145,
-.011,-.0145,
-.011,.0105,
-.010939,.011195,
-.010759,.011868,
-.010464,.0125,
-.010064,.013071,
-.009571,.013564,
-.009,.013964,
-.008368,.014259,
-.007695,.014439,
-.007,.0145,
.007,.0145,
0.0*
%
%ADD85MACRO85*%
%AMMACRO69*
4,1,40,-.012,.008,
-.012,-.008,
-.011939,-.008695,
-.011759,-.009368,
-.011464,-.01,
-.011064,-.010571,
-.010571,-.011064,
-.01,-.011464,
-.009368,-.011759,
-.008695,-.011939,
-.008,-.012,
.008,-.012,
.008695,-.011939,
.009368,-.011759,
.01,-.011464,
.010571,-.011064,
.011064,-.010571,
.011464,-.01,
.011759,-.009368,
.011939,-.008695,
.012,-.008,
.012,.008,
.011939,.008695,
.011759,.009368,
.011464,.01,
.011064,.010571,
.010571,.011064,
.01,.011464,
.009368,.011759,
.008695,.011939,
.008,.012,
-.008,.012,
-.008695,.011939,
-.009368,.011759,
-.01,.011464,
-.010571,.011064,
-.011064,.010571,
-.011464,.01,
-.011759,.009368,
-.011939,.008695,
-.012,.008,
0.0*
%
%ADD69MACRO69*%
%AMMACRO44*
4,1,40,.008,.012,
-.008,.012,
-.008695,.011939,
-.009368,.011759,
-.01,.011464,
-.010571,.011064,
-.011064,.010571,
-.011464,.01,
-.011759,.009368,
-.011939,.008695,
-.012,.008,
-.012,-.008,
-.011939,-.008695,
-.011759,-.009368,
-.011464,-.01,
-.011064,-.010571,
-.010571,-.011064,
-.01,-.011464,
-.009368,-.011759,
-.008695,-.011939,
-.008,-.012,
.008,-.012,
.008695,-.011939,
.009368,-.011759,
.01,-.011464,
.010571,-.011064,
.011064,-.010571,
.011464,-.01,
.011759,-.009368,
.011939,-.008695,
.012,-.008,
.012,.008,
.011939,.008695,
.011759,.009368,
.011464,.01,
.011064,.010571,
.010571,.011064,
.01,.011464,
.009368,.011759,
.008695,.011939,
.008,.012,
0.0*
%
%ADD44MACRO44*%
%AMMACRO35*
4,1,40,-.013,-.017,
.013,-.017,
.013695,-.016939,
.014368,-.016759,
.015,-.016464,
.015571,-.016064,
.016064,-.015571,
.016464,-.015,
.016759,-.014368,
.016939,-.013695,
.017,-.013,
.017,.013,
.016939,.013695,
.016759,.014368,
.016464,.015,
.016064,.015571,
.015571,.016064,
.015,.016464,
.014368,.016759,
.013695,.016939,
.013,.017,
-.013,.017,
-.013695,.016939,
-.014368,.016759,
-.015,.016464,
-.015571,.016064,
-.016064,.015571,
-.016464,.015,
-.016759,.014368,
-.016939,.013695,
-.017,.013,
-.017,-.013,
-.016939,-.013695,
-.016759,-.014368,
-.016464,-.015,
-.016064,-.015571,
-.015571,-.016064,
-.015,-.016464,
-.014368,-.016759,
-.013695,-.016939,
-.013,-.017,
0.0*
%
%ADD35MACRO35*%
%AMMACRO47*
4,1,40,-.017,.013,
-.017,-.013,
-.016939,-.013695,
-.016759,-.014368,
-.016464,-.015,
-.016064,-.015571,
-.015571,-.016064,
-.015,-.016464,
-.014368,-.016759,
-.013695,-.016939,
-.013,-.017,
.013,-.017,
.013695,-.016939,
.014368,-.016759,
.015,-.016464,
.015571,-.016064,
.016064,-.015571,
.016464,-.015,
.016759,-.014368,
.016939,-.013695,
.017,-.013,
.017,.013,
.016939,.013695,
.016759,.014368,
.016464,.015,
.016064,.015571,
.015571,.016064,
.015,.016464,
.014368,.016759,
.013695,.016939,
.013,.017,
-.013,.017,
-.013695,.016939,
-.014368,.016759,
-.015,.016464,
-.015571,.016064,
-.016064,.015571,
-.016464,.015,
-.016759,.014368,
-.016939,.013695,
-.017,.013,
0.0*
%
%ADD47MACRO47*%
%AMMACRO86*
4,1,25,-.26969,-.01299,
-.26969,-.83465,
.26969,-.83465,
.26969,.83465,
-.26969,.83465,
-.26969,.12087,
-.22638,.12087,
-.214758,.119853,
-.203489,.116834,
-.192915,.111903,
-.183358,.105211,
-.175109,.096962,
-.168417,.087405,
-.163486,.076831,
-.160467,.065562,
-.15945,.05394,
-.160467,.042318,
-.163486,.031049,
-.168417,.020475,
-.175109,.010918,
-.183358,.002669,
-.192915,-.004023,
-.203489,-.008954,
-.214758,-.011973,
-.22638,-.01299,
-.26969,-.01299,
0.0*
%
%ADD86MACRO86*%
%AMMACRO42*
4,1,40,.011,-.007,
.011,.007,
.010939,.007695,
.010759,.008368,
.010464,.009,
.010064,.009571,
.009571,.010064,
.009,.010464,
.008368,.010759,
.007695,.010939,
.007,.011,
-.007,.011,
-.007695,.010939,
-.008368,.010759,
-.009,.010464,
-.009571,.010064,
-.010064,.009571,
-.010464,.009,
-.010759,.008368,
-.010939,.007695,
-.011,.007,
-.011,-.007,
-.010939,-.007695,
-.010759,-.008368,
-.010464,-.009,
-.010064,-.009571,
-.009571,-.010064,
-.009,-.010464,
-.008368,-.010759,
-.007695,-.010939,
-.007,-.011,
.007,-.011,
.007695,-.010939,
.008368,-.010759,
.009,-.010464,
.009571,-.010064,
.010064,-.009571,
.010464,-.009,
.010759,-.008368,
.010939,-.007695,
.011,-.007,
0.0*
%
%ADD42MACRO42*%
%AMMACRO26*
4,1,40,.007,.011,
-.007,.011,
-.007695,.010939,
-.008368,.010759,
-.009,.010464,
-.009571,.010064,
-.010064,.009571,
-.010464,.009,
-.010759,.008368,
-.010939,.007695,
-.011,.007,
-.011,-.007,
-.010939,-.007695,
-.010759,-.008368,
-.010464,-.009,
-.010064,-.009571,
-.009571,-.010064,
-.009,-.010464,
-.008368,-.010759,
-.007695,-.010939,
-.007,-.011,
.007,-.011,
.007695,-.010939,
.008368,-.010759,
.009,-.010464,
.009571,-.010064,
.010064,-.009571,
.010464,-.009,
.010759,-.008368,
.010939,-.007695,
.011,-.007,
.011,.007,
.010939,.007695,
.010759,.008368,
.010464,.009,
.010064,.009571,
.009571,.010064,
.009,.010464,
.008368,.010759,
.007695,.010939,
.007,.011,
0.0*
%
%ADD26MACRO26*%
%AMMACRO84*
4,1,22,.011,.0145,
.011,-.0105,
.010939,-.011195,
.010759,-.011868,
.010464,-.0125,
.010064,-.013071,
.009571,-.013564,
.009,-.013964,
.008368,-.014259,
.007695,-.014439,
.007,-.0145,
-.007,-.0145,
-.007695,-.014439,
-.008368,-.014259,
-.009,-.013964,
-.009571,-.013564,
-.010064,-.013071,
-.010464,-.0125,
-.010759,-.011868,
-.010939,-.011195,
-.011,-.0105,
-.011,.0145,
.011,.0145,
0.0*
%
%ADD84MACRO84*%
%AMMACRO68*
4,1,40,-.012,.008,
-.012,-.008,
-.011939,-.008695,
-.011759,-.009368,
-.011464,-.01,
-.011064,-.010571,
-.010571,-.011064,
-.01,-.011464,
-.009368,-.011759,
-.008695,-.011939,
-.008,-.012,
.008,-.012,
.008695,-.011939,
.009368,-.011759,
.01,-.011464,
.010571,-.011064,
.011064,-.010571,
.011464,-.01,
.011759,-.009368,
.011939,-.008695,
.012,-.008,
.012,.008,
.011939,.008695,
.011759,.009368,
.011464,.01,
.011064,.010571,
.010571,.011064,
.01,.011464,
.009368,.011759,
.008695,.011939,
.008,.012,
-.008,.012,
-.008695,.011939,
-.009368,.011759,
-.01,.011464,
-.010571,.011064,
-.011064,.010571,
-.011464,.01,
-.011759,.009368,
-.011939,.008695,
-.012,.008,
0.0*
%
%ADD68MACRO68*%
%AMMACRO43*
4,1,40,.008,.012,
-.008,.012,
-.008695,.011939,
-.009368,.011759,
-.01,.011464,
-.010571,.011064,
-.011064,.010571,
-.011464,.01,
-.011759,.009368,
-.011939,.008695,
-.012,.008,
-.012,-.008,
-.011939,-.008695,
-.011759,-.009368,
-.011464,-.01,
-.011064,-.010571,
-.010571,-.011064,
-.01,-.011464,
-.009368,-.011759,
-.008695,-.011939,
-.008,-.012,
.008,-.012,
.008695,-.011939,
.009368,-.011759,
.01,-.011464,
.010571,-.011064,
.011064,-.010571,
.011464,-.01,
.011759,-.009368,
.011939,-.008695,
.012,-.008,
.012,.008,
.011939,.008695,
.011759,.009368,
.011464,.01,
.011064,.010571,
.010571,.011064,
.01,.011464,
.009368,.011759,
.008695,.011939,
.008,.012,
0.0*
%
%ADD43MACRO43*%
%AMMACRO36*
4,1,40,-.013,-.017,
.013,-.017,
.013695,-.016939,
.014368,-.016759,
.015,-.016464,
.015571,-.016064,
.016064,-.015571,
.016464,-.015,
.016759,-.014368,
.016939,-.013695,
.017,-.013,
.017,.013,
.016939,.013695,
.016759,.014368,
.016464,.015,
.016064,.015571,
.015571,.016064,
.015,.016464,
.014368,.016759,
.013695,.016939,
.013,.017,
-.013,.017,
-.013695,.016939,
-.014368,.016759,
-.015,.016464,
-.015571,.016064,
-.016064,.015571,
-.016464,.015,
-.016759,.014368,
-.016939,.013695,
-.017,.013,
-.017,-.013,
-.016939,-.013695,
-.016759,-.014368,
-.016464,-.015,
-.016064,-.015571,
-.015571,-.016064,
-.015,-.016464,
-.014368,-.016759,
-.013695,-.016939,
-.013,-.017,
0.0*
%
%ADD36MACRO36*%
%AMMACRO48*
4,1,40,-.017,.013,
-.017,-.013,
-.016939,-.013695,
-.016759,-.014368,
-.016464,-.015,
-.016064,-.015571,
-.015571,-.016064,
-.015,-.016464,
-.014368,-.016759,
-.013695,-.016939,
-.013,-.017,
.013,-.017,
.013695,-.016939,
.014368,-.016759,
.015,-.016464,
.015571,-.016064,
.016064,-.015571,
.016464,-.015,
.016759,-.014368,
.016939,-.013695,
.017,-.013,
.017,.013,
.016939,.013695,
.016759,.014368,
.016464,.015,
.016064,.015571,
.015571,.016064,
.015,.016464,
.014368,.016759,
.013695,.016939,
.013,.017,
-.013,.017,
-.013695,.016939,
-.014368,.016759,
-.015,.016464,
-.015571,.016064,
-.016064,.015571,
-.016464,.015,
-.016759,.014368,
-.016939,.013695,
-.017,.013,
0.0*
%
%ADD48MACRO48*%
%ADD52R,.135X.101*%
%ADD91R,.022X.04*%
%ADD74R,.106X.142*%
%ADD60R,.04X.023*%
%ADD71R,.06X.012*%
%ADD53R,.012X.06*%
%ADD79R,.04X.016*%
%ADD76R,.014X.06*%
%ADD32R,.045X.03*%
%AMMACRO62*
4,1,40,.013,-.023,
-.013,-.023,
-.013695,-.022939,
-.014368,-.022759,
-.015,-.022464,
-.015571,-.022064,
-.016064,-.021571,
-.016464,-.021,
-.016759,-.020368,
-.016939,-.019695,
-.017,-.019,
-.017,.019,
-.016939,.019695,
-.016759,.020368,
-.016464,.021,
-.016064,.021571,
-.015571,.022064,
-.015,.022464,
-.014368,.022759,
-.013695,.022939,
-.013,.023,
.013,.023,
.013695,.022939,
.014368,.022759,
.015,.022464,
.015571,.022064,
.016064,.021571,
.016464,.021,
.016759,.020368,
.016939,.019695,
.017,.019,
.017,-.019,
.016939,-.019695,
.016759,-.020368,
.016464,-.021,
.016064,-.021571,
.015571,-.022064,
.015,-.022464,
.014368,-.022759,
.013695,-.022939,
.013,-.023,
0.0*
%
%ADD62MACRO62*%
%ADD23R,.03X.045*%
%ADD89R,.03X.046*%
%ADD50R,.03X.064*%
%ADD82R,.045X.016*%
%ADD81R,.016X.045*%
%ADD75R,.08X.071*%
%ADD17R,.05X.065*%
%ADD58R,.065X.05*%
%ADD87R,.071X.063*%
%ADD73R,.065X.025*%
%ADD34R,.055X.035*%
%ADD14C,.315*%
%ADD66R,.09X.045*%
%ADD64R,.045X.055*%
%ADD63R,.035X.055*%
%ADD29R,.048X.016*%
%ADD72R,.055X.045*%
%ADD57R,.016X.048*%
%ADD51R,.197X.205*%
%ADD45R,.081X.065*%
%ADD56R,.065X.081*%
%ADD78R,.055X.0615*%
%ADD25R,.09X.095*%
%AMMACRO90*
4,1,40,.007,.0225,
.008389,.022378,
.009736,.022018,
.011,.021428,
.012142,.020628,
.013128,.019642,
.013928,.0185,
.014518,.017236,
.014878,.015889,
.015,.0145,
.015,-.0145,
.014878,-.015889,
.014518,-.017236,
.013928,-.0185,
.013128,-.019642,
.012142,-.020628,
.011,-.021428,
.009736,-.022018,
.008389,-.022378,
.007,-.0225,
-.007,-.0225,
-.008389,-.022378,
-.009736,-.022018,
-.011,-.021428,
-.012142,-.020628,
-.013128,-.019642,
-.013928,-.0185,
-.014518,-.017236,
-.014878,-.015889,
-.015,-.0145,
-.015,.0145,
-.014878,.015889,
-.014518,.017236,
-.013928,.0185,
-.013128,.019642,
-.012142,.020628,
-.011,.021428,
-.009736,.022018,
-.008389,.022378,
-.007,.0225,
.007,.0225,
0.0*
%
%ADD90MACRO90*%
%ADD70C,.375*%
%ADD65R,.095X.09*%
%ADD83R,.128X.128*%
%AMMACRO61*
4,1,40,-.017,-.019,
-.017,.019,
-.016939,.019695,
-.016759,.020368,
-.016464,.021,
-.016064,.021571,
-.015571,.022064,
-.015,.022464,
-.014368,.022759,
-.013695,.022939,
-.013,.023,
.013,.023,
.013695,.022939,
.014368,.022759,
.015,.022464,
.015571,.022064,
.016064,.021571,
.016464,.021,
.016759,.020368,
.016939,.019695,
.017,.019,
.017,-.019,
.016939,-.019695,
.016759,-.020368,
.016464,-.021,
.016064,-.021571,
.015571,-.022064,
.015,-.022464,
.014368,-.022759,
.013695,-.022939,
.013,-.023,
-.013,-.023,
-.013695,-.022939,
-.014368,-.022759,
-.015,-.022464,
-.015571,-.022064,
-.016064,-.021571,
-.016464,-.021,
-.016759,-.020368,
-.016939,-.019695,
-.017,-.019,
0.0*
%
%ADD61MACRO61*%
%ADD77R,.055X.06176*%
%ADD59R,.059X.089*%
%AMMACRO38*
4,1,40,.012,-.008,
.012,.008,
.011939,.008695,
.011759,.009368,
.011464,.01,
.011064,.010571,
.010571,.011064,
.01,.011464,
.009368,.011759,
.008695,.011939,
.008,.012,
-.008,.012,
-.008695,.011939,
-.009368,.011759,
-.01,.011464,
-.010571,.011064,
-.011064,.010571,
-.011464,.01,
-.011759,.009368,
-.011939,.008695,
-.012,.008,
-.012,-.008,
-.011939,-.008695,
-.011759,-.009368,
-.011464,-.01,
-.011064,-.010571,
-.010571,-.011064,
-.01,-.011464,
-.009368,-.011759,
-.008695,-.011939,
-.008,-.012,
.008,-.012,
.008695,-.011939,
.009368,-.011759,
.01,-.011464,
.010571,-.011064,
.011064,-.010571,
.011464,-.01,
.011759,-.009368,
.011939,-.008695,
.012,-.008,
0.0*
%
%ADD38MACRO38*%
%AMMACRO28*
4,1,40,-.008,-.012,
.008,-.012,
.008695,-.011939,
.009368,-.011759,
.01,-.011464,
.010571,-.011064,
.011064,-.010571,
.011464,-.01,
.011759,-.009368,
.011939,-.008695,
.012,-.008,
.012,.008,
.011939,.008695,
.011759,.009368,
.011464,.01,
.011064,.010571,
.010571,.011064,
.01,.011464,
.009368,.011759,
.008695,.011939,
.008,.012,
-.008,.012,
-.008695,.011939,
-.009368,.011759,
-.01,.011464,
-.010571,.011064,
-.011064,.010571,
-.011464,.01,
-.011759,.009368,
-.011939,.008695,
-.012,.008,
-.012,-.008,
-.011939,-.008695,
-.011759,-.009368,
-.011464,-.01,
-.011064,-.010571,
-.010571,-.011064,
-.01,-.011464,
-.009368,-.011759,
-.008695,-.011939,
-.008,-.012,
0.0*
%
%ADD28MACRO28*%
%AMMACRO24*
4,1,40,-.007,-.011,
.007,-.011,
.007695,-.010939,
.008368,-.010759,
.009,-.010464,
.009571,-.010064,
.010064,-.009571,
.010464,-.009,
.010759,-.008368,
.010939,-.007695,
.011,-.007,
.011,.007,
.010939,.007695,
.010759,.008368,
.010464,.009,
.010064,.009571,
.009571,.010064,
.009,.010464,
.008368,.010759,
.007695,.010939,
.007,.011,
-.007,.011,
-.007695,.010939,
-.008368,.010759,
-.009,.010464,
-.009571,.010064,
-.010064,.009571,
-.010464,.009,
-.010759,.008368,
-.010939,.007695,
-.011,.007,
-.011,-.007,
-.010939,-.007695,
-.010759,-.008368,
-.010464,-.009,
-.010064,-.009571,
-.009571,-.010064,
-.009,-.010464,
-.008368,-.010759,
-.007695,-.010939,
-.007,-.011,
0.0*
%
%ADD24MACRO24*%
%AMMACRO20*
4,1,40,-.011,.007,
-.011,-.007,
-.010939,-.007695,
-.010759,-.008368,
-.010464,-.009,
-.010064,-.009571,
-.009571,-.010064,
-.009,-.010464,
-.008368,-.010759,
-.007695,-.010939,
-.007,-.011,
.007,-.011,
.007695,-.010939,
.008368,-.010759,
.009,-.010464,
.009571,-.010064,
.010064,-.009571,
.010464,-.009,
.010759,-.008368,
.010939,-.007695,
.011,-.007,
.011,.007,
.010939,.007695,
.010759,.008368,
.010464,.009,
.010064,.009571,
.009571,.010064,
.009,.010464,
.008368,.010759,
.007695,.010939,
.007,.011,
-.007,.011,
-.007695,.010939,
-.008368,.010759,
-.009,.010464,
-.009571,.010064,
-.010064,.009571,
-.010464,.009,
-.010759,.008368,
-.010939,.007695,
-.011,.007,
0.0*
%
%ADD20MACRO20*%
%AMMACRO30*
4,1,40,.017,-.013,
.017,.013,
.016939,.013695,
.016759,.014368,
.016464,.015,
.016064,.015571,
.015571,.016064,
.015,.016464,
.014368,.016759,
.013695,.016939,
.013,.017,
-.013,.017,
-.013695,.016939,
-.014368,.016759,
-.015,.016464,
-.015571,.016064,
-.016064,.015571,
-.016464,.015,
-.016759,.014368,
-.016939,.013695,
-.017,.013,
-.017,-.013,
-.016939,-.013695,
-.016759,-.014368,
-.016464,-.015,
-.016064,-.015571,
-.015571,-.016064,
-.015,-.016464,
-.014368,-.016759,
-.013695,-.016939,
-.013,-.017,
.013,-.017,
.013695,-.016939,
.014368,-.016759,
.015,-.016464,
.015571,-.016064,
.016064,-.015571,
.016464,-.015,
.016759,-.014368,
.016939,-.013695,
.017,-.013,
0.0*
%
%ADD30MACRO30*%
%AMMACRO18*
4,1,40,.013,.017,
-.013,.017,
-.013695,.016939,
-.014368,.016759,
-.015,.016464,
-.015571,.016064,
-.016064,.015571,
-.016464,.015,
-.016759,.014368,
-.016939,.013695,
-.017,.013,
-.017,-.013,
-.016939,-.013695,
-.016759,-.014368,
-.016464,-.015,
-.016064,-.015571,
-.015571,-.016064,
-.015,-.016464,
-.014368,-.016759,
-.013695,-.016939,
-.013,-.017,
.013,-.017,
.013695,-.016939,
.014368,-.016759,
.015,-.016464,
.015571,-.016064,
.016064,-.015571,
.016464,-.015,
.016759,-.014368,
.016939,-.013695,
.017,-.013,
.017,.013,
.016939,.013695,
.016759,.014368,
.016464,.015,
.016064,.015571,
.015571,.016064,
.015,.016464,
.014368,.016759,
.013695,.016939,
.013,.017,
0.0*
%
%ADD18MACRO18*%
%AMMACRO67*
4,1,25,.26969,-.01299,
.26969,-.83465,
-.26969,-.83465,
-.26969,.83465,
.26969,.83465,
.26969,.12087,
.22638,.12087,
.214758,.119853,
.203489,.116834,
.192915,.111903,
.183358,.105211,
.175109,.096962,
.168417,.087405,
.163486,.076831,
.160467,.065562,
.15945,.05394,
.160467,.042318,
.163486,.031049,
.168417,.020475,
.175109,.010918,
.183358,.002669,
.192915,-.004023,
.203489,-.008954,
.214758,-.011973,
.22638,-.01299,
.26969,-.01299,
0.0*
%
%ADD67MACRO67*%
%AMMACRO37*
4,1,40,.012,-.008,
.012,.008,
.011939,.008695,
.011759,.009368,
.011464,.01,
.011064,.010571,
.010571,.011064,
.01,.011464,
.009368,.011759,
.008695,.011939,
.008,.012,
-.008,.012,
-.008695,.011939,
-.009368,.011759,
-.01,.011464,
-.010571,.011064,
-.011064,.010571,
-.011464,.01,
-.011759,.009368,
-.011939,.008695,
-.012,.008,
-.012,-.008,
-.011939,-.008695,
-.011759,-.009368,
-.011464,-.01,
-.011064,-.010571,
-.010571,-.011064,
-.01,-.011464,
-.009368,-.011759,
-.008695,-.011939,
-.008,-.012,
.008,-.012,
.008695,-.011939,
.009368,-.011759,
.01,-.011464,
.010571,-.011064,
.011064,-.010571,
.011464,-.01,
.011759,-.009368,
.011939,-.008695,
.012,-.008,
0.0*
%
%ADD37MACRO37*%
%AMMACRO27*
4,1,40,-.008,-.012,
.008,-.012,
.008695,-.011939,
.009368,-.011759,
.01,-.011464,
.010571,-.011064,
.011064,-.010571,
.011464,-.01,
.011759,-.009368,
.011939,-.008695,
.012,-.008,
.012,.008,
.011939,.008695,
.011759,.009368,
.011464,.01,
.011064,.010571,
.010571,.011064,
.01,.011464,
.009368,.011759,
.008695,.011939,
.008,.012,
-.008,.012,
-.008695,.011939,
-.009368,.011759,
-.01,.011464,
-.010571,.011064,
-.011064,.010571,
-.011464,.01,
-.011759,.009368,
-.011939,.008695,
-.012,.008,
-.012,-.008,
-.011939,-.008695,
-.011759,-.009368,
-.011464,-.01,
-.011064,-.010571,
-.010571,-.011064,
-.01,-.011464,
-.009368,-.011759,
-.008695,-.011939,
-.008,-.012,
0.0*
%
%ADD27MACRO27*%
%AMMACRO22*
4,1,40,-.007,-.011,
.007,-.011,
.007695,-.010939,
.008368,-.010759,
.009,-.010464,
.009571,-.010064,
.010064,-.009571,
.010464,-.009,
.010759,-.008368,
.010939,-.007695,
.011,-.007,
.011,.007,
.010939,.007695,
.010759,.008368,
.010464,.009,
.010064,.009571,
.009571,.010064,
.009,.010464,
.008368,.010759,
.007695,.010939,
.007,.011,
-.007,.011,
-.007695,.010939,
-.008368,.010759,
-.009,.010464,
-.009571,.010064,
-.010064,.009571,
-.010464,.009,
-.010759,.008368,
-.010939,.007695,
-.011,.007,
-.011,-.007,
-.010939,-.007695,
-.010759,-.008368,
-.010464,-.009,
-.010064,-.009571,
-.009571,-.010064,
-.009,-.010464,
-.008368,-.010759,
-.007695,-.010939,
-.007,-.011,
0.0*
%
%ADD22MACRO22*%
%AMMACRO21*
4,1,40,-.011,.007,
-.011,-.007,
-.010939,-.007695,
-.010759,-.008368,
-.010464,-.009,
-.010064,-.009571,
-.009571,-.010064,
-.009,-.010464,
-.008368,-.010759,
-.007695,-.010939,
-.007,-.011,
.007,-.011,
.007695,-.010939,
.008368,-.010759,
.009,-.010464,
.009571,-.010064,
.010064,-.009571,
.010464,-.009,
.010759,-.008368,
.010939,-.007695,
.011,-.007,
.011,.007,
.010939,.007695,
.010759,.008368,
.010464,.009,
.010064,.009571,
.009571,.010064,
.009,.010464,
.008368,.010759,
.007695,.010939,
.007,.011,
-.007,.011,
-.007695,.010939,
-.008368,.010759,
-.009,.010464,
-.009571,.010064,
-.010064,.009571,
-.010464,.009,
-.010759,.008368,
-.010939,.007695,
-.011,.007,
0.0*
%
%ADD21MACRO21*%
%ADD92C,.02*%
%ADD93C,.012*%
%ADD94C,.04*%
%ADD95C,.014*%
%ADD96C,.015*%
%ADD97C,.016*%
%ADD98C,.025*%
%ADD99C,.018*%
%ADD100C,.006*%
%ADD101C,.0055*%
%ADD111C,.05204*%
%ADD107C,.08004*%
%ADD109C,.08104*%
%ADD108R,.13204X.13204*%
%ADD105C,.15004*%
%ADD103C,.12304*%
%ADD104C,.13904*%
%ADD102C,.16604*%
%ADD106C,.33904*%
%ADD110C,.39904*%
G75*
%LPD*%
G75*
G36*
G01X202756Y1926133D02*
G02X203692Y1925197I0J-936D01*
G01Y528392D01*
X202600Y527300D01*
X173700D01*
X173000Y528000D01*
Y529545D01*
G02X173587Y529898I400J-1D01*
G03X175429Y534725I1213J2302D01*
G01X175375Y534738D01*
X175312Y534802D01*
X174849D01*
G03X174751I-49J-2602D01*
G01X173000D01*
Y535535D01*
G03X173002Y535600I-1599J82D01*
G01Y537200D01*
G03X173000Y537265I-1601J-17D01*
G01Y538000D01*
X172000Y539000D01*
X168500D01*
X167500Y540000D01*
Y545000D01*
X168148Y545648D01*
X176052D01*
Y545771D01*
G02X176734Y546054I400J0D01*
G01X180294Y542494D01*
X180289Y542406D01*
G03X182470Y544587I2299J-118D01*
G01X182382Y544582D01*
X176388Y550576D01*
X176052D01*
Y552552D01*
X168737D01*
X168602Y552687D01*
Y554600D01*
G03X167000Y556202I-1602J0D01*
G01X165087D01*
X161776Y559512D01*
Y559612D01*
X161335Y560053D01*
G02X161378Y560656I283J283D01*
G03X159882Y564799I-1378J1844D01*
G01X159794Y564794D01*
X158576Y566012D01*
Y572700D01*
G02X158768Y572900I200J0D01*
G03X160302Y574500I-67J1600D01*
G01Y575900D01*
G03X159951Y576900I-1602J-1D01*
G03X160302Y577900I-1251J1001D01*
G01Y579300D01*
G03X158700Y580902I-1602J0D01*
G01X158312D01*
X156633Y582581D01*
X156619Y582606D01*
G03X153494Y579481I-2019J-1106D01*
G01X153519Y579467D01*
X155953Y577034D01*
X155964Y577017D01*
G03X156049Y576900I1337J882D01*
G03X155698Y575900I1251J-1001D01*
G01Y574937D01*
X155624Y574862D01*
Y569020D01*
G02X155019Y568676I-400J0D01*
G03X154200Y568902I-820J-1376D01*
G01X152800D01*
G03X151413Y568100I1J-1602D01*
G01X151399Y568077D01*
X151239Y567917D01*
X151001Y568155D01*
Y572475D01*
G03X151407Y576370I-1501J2125D01*
G02X151414Y576650I146J136D01*
G03X151902Y577800I-1114J1151D01*
G01Y579400D01*
G03X150300Y581002I-1602J0D01*
G01X148700D01*
G03X148598Y580998I12J-1602D01*
G01X148508Y580992D01*
X148200Y581300D01*
Y583400D01*
X150202Y585402D01*
G02X150807Y585355I282J-283D01*
G03X152100Y584698I1293J944D01*
G01X153500D01*
G03X154500Y585049I-1J1602D01*
G03X155500Y584698I1001J1251D01*
G01X156900D01*
G03X158484Y586065I0J1601D01*
G01X158494Y586130D01*
X161452Y589088D01*
Y589577D01*
X161460Y589604D01*
G03X159146Y592550I-2210J646D01*
G02X158845Y593232I-18J400D01*
G01X160736Y595123D01*
Y595936D01*
X164398Y599598D01*
X174815D01*
X175216Y600000D01*
X178500D01*
X186500Y608000D01*
Y648500D01*
X185396Y649604D01*
Y649918D01*
X163312Y672002D01*
X156498D01*
X155000Y673500D01*
Y676500D01*
X155769Y677269D01*
X155819Y677283D01*
G03X157417Y678881I-619J2217D01*
G01X157431Y678931D01*
X160500Y682000D01*
X174000D01*
X180000Y688000D01*
Y703500D01*
X179941Y703559D01*
G02X180011Y703887I142J141D01*
G03X176293Y707225I-1011J2613D01*
G01X176254Y707076D01*
X170522D01*
Y714306D01*
X159038D01*
Y706976D01*
X157726D01*
Y714306D01*
X156871D01*
G02X156588Y714988I0J400D01*
G01X163650Y722050D01*
X166550D01*
X168500Y724000D01*
Y728102D01*
X173076D01*
Y736506D01*
X164106D01*
X163900Y736300D01*
Y729400D01*
X163600Y729100D01*
X160900D01*
X160500Y729500D01*
Y736400D01*
X160000Y736900D01*
X154500D01*
X154106Y736506D01*
X153924D01*
Y736324D01*
X153550Y735950D01*
Y726550D01*
X152300Y725300D01*
X143100D01*
X141300Y727100D01*
X138102D01*
Y733502D01*
X137602D01*
Y735266D01*
X152734Y750398D01*
X157927D01*
X157954Y750390D01*
G03Y754810I646J2210D01*
G01X157927Y754802D01*
X150910D01*
X133198Y737090D01*
Y733502D01*
X132698D01*
Y730602D01*
X127363D01*
G03X126200Y731102I-1163J-1103D01*
G01X123600D01*
G03X121998Y729500I0J-1602D01*
G01Y727666D01*
G02X121316Y727383I-400J0D01*
G01X120498Y728202D01*
X115502D01*
X113798Y726498D01*
Y723002D01*
X118002Y718798D01*
X120502D01*
X125298Y714002D01*
Y705502D01*
X127002Y703798D01*
X138600D01*
Y698900D01*
X140800Y696700D01*
X141499D01*
G02X141898Y696300I-1J-400D01*
G01Y694700D01*
G03X142774Y693273I1602J1D01*
G01Y690388D01*
X142798Y690363D01*
Y686298D01*
X148202D01*
Y688513D01*
X148642Y688954D01*
X148875Y688721D01*
X148829Y688599D01*
G03X152072Y685749I2149J-824D01*
G01X152116Y685774D01*
X152373D01*
G03X152549Y685500I1428J724D01*
G03X152198Y684500I1251J-1001D01*
G01Y684198D01*
X152000Y684000D01*
Y683338D01*
X151524Y682862D01*
Y677024D01*
X150500Y676000D01*
X149500D01*
X144500Y681000D01*
X144326D01*
Y685702D01*
X138924D01*
Y680424D01*
X138481Y679981D01*
X137366Y681096D01*
X132000D01*
Y693500D01*
X131000Y694500D01*
X117758D01*
Y694867D01*
X113133D01*
X113000Y695000D01*
X109500D01*
X109367Y694867D01*
X108854D01*
Y694354D01*
X108500Y694000D01*
Y674013D01*
X107788Y673302D01*
X105788D01*
X103736Y671250D01*
G02X103073Y671408I-283J283D01*
G03X98457Y672076I-2473J-808D01*
G01X96963D01*
X96917Y672212D01*
G03X95400Y673302I-1517J-511D01*
G01X94682D01*
Y674500D01*
X97500D01*
X98000Y675000D01*
Y694500D01*
X97658Y694842D01*
Y694866D01*
X97634D01*
X96000Y696500D01*
X88314D01*
G03X84005Y696796I-2254J-1300D01*
G02X83480Y696701I-316J246D01*
G03X82646Y696936I-835J-1366D01*
G01X81244D01*
G03X79642Y695335I0J-1602D01*
G01Y693935D01*
G03X79767Y693316I1602J1D01*
G02X79370Y692762I-369J-155D01*
G03X79258Y692766I-113J-1597D01*
G01X77863D01*
X77832Y692929D01*
G03X76476Y694612I-2261J-434D01*
G01Y699638D01*
X77037Y700198D01*
X78000D01*
Y699500D01*
X85000D01*
X88500Y703000D01*
X89698D01*
G03X92748Y702952I1552J1700D01*
G01X92804Y703000D01*
X93000D01*
X94500Y704500D01*
Y710798D01*
X109498D01*
X112102Y713402D01*
Y761311D01*
X112213Y761366D01*
G03X113102Y762800I-712J1434D01*
G01Y765400D01*
G03X112694Y766467I-1602J-1D01*
G02Y766733I150J133D01*
G03X113102Y767800I-1194J1068D01*
G01Y770400D01*
G03X112213Y771834I-1601J0D01*
G01X112102Y771889D01*
Y813098D01*
X107498Y817702D01*
X88502D01*
X87198Y816398D01*
Y789698D01*
X86500Y789000D01*
X69500D01*
X60000Y779500D01*
X20500D01*
X19790Y780210D01*
X19814Y780317D01*
G03X19519Y782901I-3908J863D01*
G01X19500Y782942D01*
Y783500D01*
X17500Y785500D01*
X11500D01*
X10500Y784500D01*
Y776699D01*
X8798Y774998D01*
Y767002D01*
X10500Y765301D01*
Y735000D01*
X11000Y734500D01*
X43500D01*
X61750Y716250D01*
X76500D01*
X77000Y715750D01*
Y708500D01*
X78500Y707000D01*
Y705191D01*
G02X78060Y704793I-400J0D01*
G03X77900Y704802I-170J-1592D01*
G01X76500D01*
G03X75701Y704588I1J-1602D01*
G02X75102Y704934I-199J347D01*
G01Y706700D01*
G03X73500Y708302I-1602J0D01*
G01X70900D01*
G03X69833Y707894I1J-1602D01*
G02X69567I-133J150D01*
G03X68500Y708302I-1068J-1194D01*
G01X65900D01*
G03X64298Y706700I0J-1602D01*
G01Y704100D01*
G03X64726Y703011I1602J1D01*
G01X64857Y702870D01*
X61827Y699840D01*
X58357D01*
G03X58295Y699858I-673J-2201D01*
G01X56152Y702002D01*
X51968D01*
G02X51603Y702564I0J400D01*
G03X49173Y705779I-2103J936D01*
G02X48729Y706075I-57J396D01*
G03X44734Y706976I-2229J-575D01*
G01X41913D01*
X31598Y696662D01*
Y688313D01*
X32648Y687263D01*
Y685998D01*
X39148D01*
Y683438D01*
X42663D01*
X45218Y680884D01*
G02X44935Y680202I-283J-282D01*
G01X37312D01*
X31802Y685712D01*
Y686600D01*
G03X30200Y688202I-1602J0D01*
G01X27600D01*
G03X26500Y687764I1J-1602D01*
G03X25400Y688202I-1101J-1164D01*
G01X22800D01*
G03X21198Y686600I0J-1602D01*
G01Y684000D01*
G03X22800Y682398I1602J0D01*
G01X25400D01*
G03X26500Y682836I-1J1602D01*
G03X27600Y682398I1101J1164D01*
G01X28888D01*
X35488Y675798D01*
X35816D01*
G02X35957Y675457I0J-200D01*
G01X35500Y675000D01*
Y645549D01*
G02X34926Y645188I-400J-1D01*
G03X29579Y613090I-7367J-15267D01*
G02X29910Y612410I48J-397D01*
G01X7300Y589800D01*
Y513900D01*
X6500Y513100D01*
Y506500D01*
X8000Y505000D01*
X12949D01*
G02X13218Y504304I0J-400D01*
G03X18594I2688J-2965D01*
G02X18863Y505000I269J296D01*
G01X25000D01*
X30000Y500000D01*
Y487500D01*
X37500Y480000D01*
Y462948D01*
G02X36770Y462722I-400J0D01*
G03Y453340I-6849J-4691D01*
G02X37500Y453114I330J-226D01*
G01Y356500D01*
X37282Y356282D01*
X35002Y358562D01*
X35000Y358643D01*
G03X33533Y355611I-3701J-80D01*
G01X33672Y355716D01*
X36500Y352888D01*
Y350040D01*
X34694D01*
G03Y347086I-3395J-1477D01*
G01X36500D01*
Y338000D01*
X35225Y336725D01*
X34745Y337205D01*
X34787Y337324D01*
G03X32538Y335075I-3488J1239D01*
G01X32657Y335117D01*
X33137Y334637D01*
X32500Y334000D01*
X23900D01*
X23872Y334168D01*
G03X19328I-2272J-368D01*
G01X19300Y334000D01*
X16500D01*
X14500Y332000D01*
Y303500D01*
X17500Y300500D01*
X19228D01*
X19257Y300491D01*
G03X20763I753J2491D01*
G01X20792Y300500D01*
X35500D01*
X36000Y300000D01*
Y287500D01*
X40500Y283000D01*
X68200D01*
Y278779D01*
G02X67517Y278496I-400J0D01*
G01X63812Y282202D01*
X61558D01*
X61526Y282213D01*
G03X61000Y282302I-527J-1513D01*
G01X59600D01*
G03X58600Y281951I1J-1602D01*
G03X57600Y282302I-1001J-1251D01*
G01X56200D01*
G03X54799Y281476I0J-1601D01*
G01X47388D01*
X46006Y280094D01*
X45918Y280099D01*
G03X48099Y277918I-118J-2299D01*
G01X48094Y278006D01*
X48612Y278524D01*
X54799D01*
G03X56200Y277698I1401J775D01*
G01X57600D01*
G03X58600Y278049I-1J1602D01*
G03X58877Y277871I1000J1251D01*
G02X58908Y277533I-90J-179D01*
G03X58524Y274236I1392J-1833D01*
G01Y271129D01*
G02X58031Y270740I-400J0D01*
G03X55201Y268382I-531J-2240D01*
G01X55206Y268294D01*
X52824Y265912D01*
Y265401D01*
G03X51998Y264000I775J-1401D01*
G01Y262600D01*
G03X52349Y261600I1602J1D01*
G03X51998Y260600I1251J-1001D01*
G01Y259200D01*
G03X52824Y257799I1601J0D01*
G01Y254288D01*
X53298Y253813D01*
Y251500D01*
G03X54900Y249898I1602J0D01*
G01X57213D01*
X59338Y247774D01*
X59827D01*
X60437Y247163D01*
X60394Y247044D01*
G03X60298Y246500I1506J-546D01*
G01Y245100D01*
G03X60387Y244574I1602J1D01*
G01X60398Y244542D01*
Y242838D01*
X60594Y242643D01*
G02X60453Y242301I-141J-142D01*
G01X60300D01*
G03X59220Y241882I0J-1601D01*
G02X58680I-270J296D01*
G03X57600Y242302I-1081J-1182D01*
G01X56200D01*
G03X54598Y240700I0J-1602D01*
G01Y239300D01*
G03X56200Y237698I1602J0D01*
G01X57600D01*
G03X58456Y237946I0J1601D01*
G02X58756Y237724I107J-169D01*
G03X58704Y237434I1544J-426D01*
G01X58698Y237361D01*
X56343Y235007D01*
X56318Y234993D01*
G03X55392Y234055I1107J-2018D01*
G01X55338Y234002D01*
X45822D01*
X44753Y235071D01*
X44739Y235096D01*
G03X40490Y233419I-2019J-1106D01*
G02X40360Y233180I-194J-49D01*
G03X38803Y231146I740J-2180D01*
G02X38344Y230776I-399J26D01*
G03X38118Y226201I-344J-2276D01*
G01X38206Y226206D01*
X38838Y225574D01*
X41800D01*
Y182500D01*
G03X41768Y179949I1900J-1300D01*
G01X41800Y179899D01*
Y178876D01*
X34510D01*
G03X33605Y175924I-2085J-976D01*
G01X36598D01*
G02X36998Y175520I0J-400D01*
G03X38020Y173587I2302J-20D01*
G01X38036Y173576D01*
X48224Y163388D01*
Y160888D01*
X54599Y154513D01*
X54606Y154442D01*
G03X56200Y152998I1594J158D01*
G01X57600D01*
G03X59202Y154600I0J1602D01*
G01Y156063D01*
X60137Y156998D01*
X61000D01*
G03X62387Y157800I-1J1602D01*
G01X73600D01*
G02X73852Y157089I0J-400D01*
G03X73191Y156222I1448J-1789D01*
G01X73176Y156188D01*
X63989Y147002D01*
X58887D01*
X52184Y153704D01*
X52171Y153761D01*
G03X50529Y151040I-2247J-500D01*
G01X50641Y151071D01*
X57663Y144048D01*
X65213D01*
X74359Y153195D01*
X74480Y153149D01*
G03X77566Y155704I820J2151D01*
G02X78243Y156057I394J70D01*
G01X78900Y155400D01*
X109500D01*
X109550Y155450D01*
X113450D01*
X141000Y183000D01*
Y193500D01*
X144900Y197400D01*
X185500D01*
X189000Y200900D01*
Y312500D01*
X178500Y323000D01*
Y426500D01*
X183000Y431000D01*
X186500D01*
X188904Y433404D01*
X189025Y433360D01*
G03X189065Y433345I934J2429D01*
G01X189198Y433298D01*
Y433078D01*
X189190Y433051D01*
G03X193505Y431472I2210J-646D01*
G01X193520Y431506D01*
X196452Y434438D01*
Y435452D01*
X196500Y435500D01*
Y438735D01*
G03X196502Y438800I-1599J82D01*
G01Y440200D01*
G03X196500Y440265I-1601J-17D01*
G01Y441500D01*
X197000Y442000D01*
X201692D01*
X203692Y440000D01*
Y279192D01*
X203346Y278846D01*
X203692Y278500D01*
Y43307D01*
G02X202756Y42371I-936J0D01*
G01X72835D01*
G03X65897Y35433I0J-6938D01*
G01Y3937D01*
G02X64961Y3001I-936J0D01*
G01X3937D01*
G02X3001Y3937I0J936D01*
G01Y1328776D01*
G02X3731Y1329002I400J0D01*
G03Y1348164I13985J9581D01*
G02X3001Y1348390I-330J226D01*
G01Y1964567D01*
G02X3937Y1965503I936J0D01*
G01X64961D01*
G02X65897Y1964567I0J-936D01*
G01Y1933071D01*
G03X72835Y1926133I6938J0D01*
G01X202756D01*
G37*
G36*
G01X40000Y480000D02*
X31202Y488798D01*
Y500498D01*
X31000Y500699D01*
Y517500D01*
X31100Y517600D01*
Y521300D01*
X35600Y525800D01*
X87022D01*
X87049Y525792D01*
G03X88351I651J2208D01*
G01X88378Y525800D01*
X91600D01*
X91750Y525650D01*
X96350D01*
X96500Y525800D01*
X111100D01*
X111198Y525898D01*
X152098D01*
X152299Y526100D01*
X155100D01*
X155800Y525400D01*
X173000D01*
X173698Y526098D01*
X202902D01*
X203500Y525500D01*
Y481000D01*
X202500Y480000D01*
X185300D01*
X184300Y481000D01*
Y484900D01*
X183600Y485600D01*
X151400D01*
X150800Y485000D01*
Y481400D01*
X149400Y480000D01*
X143746D01*
G03X140254I-1746J-1500D01*
G01X99400D01*
X97700Y481700D01*
Y484400D01*
X95800Y486300D01*
X66900D01*
X60802Y480202D01*
X42502D01*
X42301Y480000D01*
X40000D01*
G37*
G36*
G01X21800Y579096D02*
G03X21798Y575887I1650J-1606D01*
G01Y572639D01*
X21796Y572637D01*
Y568963D01*
X21798Y568961D01*
Y564870D01*
X21800Y564869D01*
Y546368D01*
X21796Y546348D01*
G03Y542944I8125J-1702D01*
G01X21800Y542924D01*
Y538000D01*
X21850Y537950D01*
Y530550D01*
X29700Y522700D01*
Y513300D01*
X24400Y508000D01*
X19183D01*
G02X18885Y508667I0J400D01*
G03X12927I-2979J2672D01*
G02X12629Y508000I-298J-267D01*
G01X9000D01*
X7702Y509298D01*
Y512602D01*
X8502Y513402D01*
Y589302D01*
X15316Y596117D01*
X15317Y596118D01*
G03X15382Y596183I-1807J1872D01*
G01X15383Y596184D01*
X33099Y613900D01*
X33142Y613915D01*
G03X39611Y618000I-5583J16006D01*
G01X82000D01*
X85550Y614450D01*
Y601950D01*
X82100Y598500D01*
X72598D01*
G03X72402I-98J-2600D01*
G01X37000D01*
X21800Y583300D01*
Y579096D01*
G37*
G36*
G01X27000Y534000D02*
X29363Y536363D01*
X29452Y536358D01*
G03X33500Y552136I469J8288D01*
G01Y559500D01*
X35000Y561000D01*
X58500D01*
X61000Y563500D01*
X68736D01*
G03X72011Y563457I1664J2000D01*
G01X72066Y563500D01*
X72500D01*
X75498Y566498D01*
X79502D01*
X81628Y564372D01*
Y557128D01*
X81500Y557000D01*
X75925D01*
G03X74600Y557702I-1325J-899D01*
G01X73200D01*
G03X71598Y556100I0J-1602D01*
G01Y555099D01*
X71500Y555000D01*
Y551546D01*
G03Y548654I2400J-1446D01*
G01Y544562D01*
X71489Y544530D01*
G03X71398Y544000I1511J-532D01*
G01Y542600D01*
G03X71489Y542070I1602J2D01*
G01X71500Y542038D01*
Y541162D01*
X71489Y541130D01*
G03X71398Y540600I1511J-532D01*
G01Y539200D01*
G03X71489Y538670I1602J2D01*
G01X71500Y538638D01*
Y536500D01*
X73500Y534500D01*
X75521D01*
G03X76771Y533775I1879J1800D01*
G01X76825Y533762D01*
X78838Y531748D01*
X79133D01*
Y531529D01*
X79129Y531510D01*
G03X79098Y531200I1571J-314D01*
G01Y529800D01*
G03X80700Y528198I1602J0D01*
G01X82100D01*
G03X82475Y528243I-2J1602D01*
G01X82498Y528248D01*
X83283D01*
G02X83566Y527566I0J-400D01*
G01X83300Y527300D01*
X27400D01*
X27000Y527700D01*
Y534000D01*
G37*
G36*
G01X62000Y572588D02*
X53489Y564078D01*
X28500D01*
Y566500D01*
X30000Y568000D01*
X34000D01*
X34568Y568568D01*
X34612Y568583D01*
G03X35702Y570100I-511J1517D01*
G01Y571500D01*
G03X35657Y571875I-1602J-2D01*
G01X35652Y571898D01*
Y572152D01*
X38500Y575000D01*
X42549D01*
G03X43800Y574398I1251J999D01*
G01X46400D01*
G03X47594Y574933I-1J1602D01*
G01X47654Y575000D01*
X47837D01*
X47892Y574955D01*
G03X48900Y574598I1008J1245D01*
G01X50300D01*
G03X51361Y575000I0J1601D01*
G01X55077D01*
G03X58523I1723J1950D01*
G01X59738D01*
X59770Y574989D01*
G03X60300Y574898I532J1511D01*
G01X61102D01*
X62000Y574000D01*
Y572588D01*
G37*
G36*
G01X57932Y752480D02*
X66888Y743524D01*
X66976D01*
X68000Y742500D01*
X72062D01*
X72798Y741763D01*
Y740700D01*
G03X74400Y739098I1602J0D01*
G01X75463D01*
X75638Y738924D01*
X77000D01*
Y735000D01*
X78000Y734000D01*
Y730000D01*
X77702Y729702D01*
X76300D01*
G03X75564Y729522I2J-1602D01*
G01X75521Y729500D01*
X74746D01*
G03X71638Y729856I-1746J-1500D01*
G02X71002Y730178I-236J322D01*
G01Y730700D01*
G03X69400Y732302I-1602J0D01*
G01X68000D01*
G03X67000Y731951I1J-1602D01*
G03X66000Y732302I-1001J-1251D01*
G01X64600D01*
G03X63350Y731702I0J-1602D01*
G01X62205D01*
X53205Y740702D01*
X24798D01*
X20702Y744798D01*
Y748792D01*
X20500Y748993D01*
Y757000D01*
X22000Y758500D01*
X23912D01*
X29932Y752480D01*
X57932D01*
G37*
G36*
G01X18747Y764000D02*
G03X13427Y764323I-2841J-2819D01*
G01X13287Y764213D01*
X10000Y767500D01*
Y774500D01*
X12500Y777000D01*
X60000D01*
X70000Y787000D01*
X81000D01*
X84000Y784000D01*
Y769400D01*
X83300Y768700D01*
Y747300D01*
X81000Y745000D01*
X73738D01*
X72262Y746476D01*
X68112D01*
X67000Y747588D01*
Y760000D01*
X63000Y764000D01*
X53598D01*
G03X40890I-6354J-2819D01*
G01X18747D01*
G37*
G36*
G01X79081Y431533D02*
X78698Y431916D01*
G02X78981Y432598I283J282D01*
G01X82712D01*
X85712Y435598D01*
X86702D01*
Y443114D01*
X87552D01*
Y443500D01*
X89078D01*
X89104Y443493D01*
G03X90496I696J2507D01*
G01X90522Y443500D01*
X92948D01*
Y442614D01*
X108500D01*
Y436000D01*
X107500Y435000D01*
X103000D01*
X96818Y428818D01*
X96791Y428804D01*
G03X95696Y427709I1209J-2304D01*
G01X95682Y427682D01*
X95000Y427000D01*
Y375300D01*
X95100Y375200D01*
Y374900D01*
X92500Y372300D01*
Y352700D01*
X94200Y351000D01*
X103500D01*
X106500Y348000D01*
Y316500D01*
X120000Y303000D01*
Y262400D01*
X115314Y257714D01*
G02X114643Y257901I-283J283D01*
G03X107313Y254718I-3934J-973D01*
G02X106978Y254100I-335J-218D01*
G01X104440D01*
G02X104105Y254718I0J400D01*
G03X97313I-3396J2211D01*
G02X96978Y254100I-335J-218D01*
G01X94440D01*
G02X94105Y254718I0J400D01*
G03X87313I-3396J2211D01*
G02X86978Y254100I-335J-218D01*
G01X84440D01*
G02X84105Y254718I0J400D01*
G03X76659Y256818I-3396J2211D01*
G02X75976Y256524I-400J-11D01*
G01X72100Y260400D01*
Y281200D01*
X69402Y283899D01*
Y284202D01*
X69098D01*
X68800Y284500D01*
X41000D01*
X38000Y287500D01*
Y315115D01*
X44976Y322091D01*
Y322476D01*
X45000Y322500D01*
Y348500D01*
X44976Y348524D01*
Y348588D01*
X38750Y354814D01*
Y435250D01*
X47000Y443500D01*
X65448D01*
Y443114D01*
X81298D01*
Y437412D01*
X80888Y437002D01*
X72388D01*
X68548Y433162D01*
Y432398D01*
X68543Y432375D01*
G03X68498Y432000I1557J-377D01*
G01Y430600D01*
G03X68543Y430225I1602J2D01*
G01X68548Y430202D01*
Y428314D01*
G03X73018Y428711I2352J-1114D01*
G02X73217Y429024I163J116D01*
G03X73500Y428998I287J1576D01*
G01X74900D01*
G03X75227Y429032I-1J1602D01*
G01X75332Y429054D01*
X75967Y428419D01*
X75981Y428394D01*
G03X79106Y431519I2019J1106D01*
G01X79081Y431533D01*
G37*
G36*
G01X41750Y444250D02*
X40500Y445500D01*
Y476500D01*
X43000Y479000D01*
X97000D01*
X97250Y478750D01*
X100650D01*
G02X101040Y478260I0J-400D01*
G03X100998Y477900I1559J-364D01*
G01Y475300D01*
G03X102600Y473698I1602J0D01*
G01X105200D01*
G03X106801Y475254I0J1602D01*
G01X106806Y475448D01*
X107427D01*
X107454Y475440D01*
G03X110323Y478246I646J2210D01*
G02X110710Y478750I386J104D01*
G01X120750D01*
X124500Y475000D01*
Y450000D01*
X119046Y444546D01*
X118944Y444564D01*
G03X117193Y444250I-444J-2564D01*
G01X108949D01*
X108498Y444702D01*
X46502D01*
X46051Y444250D01*
X41750D01*
G37*
G36*
G01X90863Y592813D02*
Y585223D01*
X95250Y580837D01*
Y579250D01*
X92000Y576000D01*
X89364D01*
G03X88200Y576502I-1165J-1100D01*
G01X87455D01*
X87355Y576602D01*
X87005D01*
X85320Y578286D01*
Y579773D01*
G03X81918I-1701J1969D01*
G01Y576909D01*
G03X80327Y574889I982J-2410D01*
G01X80317Y574824D01*
X78895Y573402D01*
X77900D01*
G03X76892Y573045I0J-1602D01*
G01X76837Y573000D01*
X76567D01*
X76509Y573056D01*
G03X75400Y573502I-1109J-1156D01*
G01X72800D01*
G03X71198Y571900I0J-1602D01*
G01Y571500D01*
X68500D01*
X68000Y572000D01*
Y577500D01*
X71000Y580500D01*
X73500D01*
X74048Y581048D01*
X75602D01*
Y586952D01*
X75500D01*
Y587500D01*
X76500Y588500D01*
X79500D01*
X79930Y588930D01*
X79950Y588942D01*
G03X80458Y589450I-850J1358D01*
G01X80470Y589470D01*
X82000Y591000D01*
Y595000D01*
X85000Y598000D01*
X90000D01*
X90764Y597236D01*
Y596771D01*
G03X90974Y595978I1602J0D01*
G01X91000Y595932D01*
Y595610D01*
X90974Y595564D01*
G03X90764Y594771I1392J-793D01*
G01Y593371D01*
G03X90852Y592845I1601J-2D01*
G01X90863Y592813D01*
G37*
G36*
G01X47588Y675798D02*
X50967Y672419D01*
X50981Y672394D01*
G03X54692Y671939I2019J1106D01*
G02X55328Y671874I294J-272D01*
G03X55724Y671431I1371J827D01*
G01Y670027D01*
G03X59343Y666408I1476J-2143D01*
G01X60226D01*
G02X60367Y666066I0J-200D01*
G01X60298Y665998D01*
Y655002D01*
X66502Y648798D01*
X67202D01*
X69000Y647000D01*
X77200D01*
X84798Y639402D01*
Y637298D01*
X84850D01*
Y626350D01*
X81000Y622500D01*
X49600D01*
X47200Y624900D01*
Y635000D01*
X36702Y645498D01*
Y674502D01*
X37998Y675798D01*
X47588D01*
G37*
G36*
G01X75587Y677000D02*
X80914Y671673D01*
G02X80667Y670992I-283J-283D01*
G03X79624Y666133I233J-2591D01*
G01Y658188D01*
X92324Y645488D01*
Y638500D01*
X86000D01*
Y640500D01*
X76500Y650000D01*
X67000D01*
X61500Y655500D01*
Y665500D01*
X62408Y666408D01*
X62496D01*
X64587Y668498D01*
X65962D01*
X65963Y668500D01*
X66500D01*
X69004Y671004D01*
X71436D01*
Y673436D01*
X71500Y673500D01*
Y677000D01*
X75587D01*
G37*
G36*
G01X88912Y669902D02*
X83687Y675127D01*
G02X83952Y675809I283J283D01*
G03X86138Y678358I-102J2300D01*
G02X86545Y678802I398J44D01*
G03X87497Y678984I53J2301D01*
G01X87534Y679000D01*
X88000D01*
Y676000D01*
X88754Y675246D01*
Y674964D01*
X89036D01*
X89500Y674500D01*
X91730D01*
Y671932D01*
X92398Y671263D01*
Y670300D01*
G03X92408Y670124I1602J3D01*
G01X92409Y670113D01*
Y669902D01*
X88912D01*
G37*
G36*
G01X52589Y679500D02*
X50013Y682076D01*
X48202D01*
X46352Y683927D01*
Y687442D01*
X39852D01*
Y688558D01*
X46352D01*
Y688751D01*
G02X46693Y688893I200J0D01*
G01X48148Y687437D01*
Y685998D01*
X54648D01*
Y683438D01*
X55137D01*
Y683144D01*
X55063Y683084D01*
G03X54313Y680056I1647J-2015D01*
G02X53945Y679500I-368J-156D01*
G01X52589D01*
G37*
G36*
G01X74898Y702237D02*
X73524Y700862D01*
Y693548D01*
G03X73277Y692684I2047J-1053D01*
G01X73262Y692500D01*
X67500D01*
X66208Y691208D01*
X64335D01*
G03X62734Y689606I0J-1601D01*
G01Y688318D01*
X61857Y687442D01*
X55352D01*
Y688558D01*
X61852D01*
Y692562D01*
X60252D01*
Y695438D01*
X63651D01*
X69502Y701288D01*
Y702365D01*
G02X70101Y702712I400J0D01*
G03X70900Y702498I800J1388D01*
G01X73500D01*
G03X74299Y702712I-1J1602D01*
G02X74898Y702365I199J-347D01*
G01Y702237D01*
G37*
G36*
G01X51026Y692562D02*
X46717Y696871D01*
X46742Y696979D01*
G03X46800Y697584I-2242J520D01*
G02X47200Y697998I400J14D01*
G01X54494D01*
X55464Y697029D01*
X55478Y696980D01*
G03X56248Y695839I2206J658D01*
G01Y692562D01*
X51026D01*
G37*
G36*
G01X114000Y382178D02*
Y389278D01*
X114007Y389304D01*
G03Y390696I-2507J696D01*
G01X114000Y390722D01*
Y428300D01*
X120898Y435198D01*
X122000D01*
G03X123602Y436800I0J1602D01*
G01Y437901D01*
X128500Y442800D01*
X137448D01*
Y442614D01*
X153298D01*
Y435098D01*
X153798D01*
Y434162D01*
X152739Y433102D01*
X152666Y433096D01*
G03X151800Y432751I134J-1596D01*
G03X150800Y433102I-1001J-1251D01*
G01X149372D01*
X148992Y433481D01*
G03X145854Y430381I-2032J-1081D01*
G01X145879Y430367D01*
X147648Y428598D01*
X148842D01*
X148874Y428587D01*
G03X149400Y428498I527J1513D01*
G01X150800D01*
G03X151800Y428849I-1J1602D01*
G03X152800Y428498I1001J1251D01*
G01X154200D01*
G03X155784Y429865I0J1601D01*
G01X155794Y429930D01*
X158202Y432338D01*
Y435098D01*
X158702D01*
Y437298D01*
X160160D01*
G03X163241Y440694I2452J871D01*
G01X163187Y440707D01*
X162193Y441702D01*
X158702D01*
Y442614D01*
X159552D01*
Y442800D01*
X165448D01*
Y442614D01*
X176500D01*
Y442500D01*
X179500D01*
X180000Y442000D01*
Y431500D01*
X177500Y429000D01*
Y427199D01*
X177298Y426998D01*
Y322502D01*
X177500Y322301D01*
Y321500D01*
X177300Y321300D01*
X187050Y311550D01*
X187000Y311500D01*
Y252500D01*
X185500Y251000D01*
X145500D01*
X140500Y256000D01*
Y285500D01*
X109500Y316500D01*
Y349000D01*
X111000Y350500D01*
X114500D01*
X117400Y353400D01*
Y373300D01*
X114000Y376700D01*
Y378022D01*
G03X114202Y378800I-1400J779D01*
G01Y381400D01*
G03X114000Y382178I-1602J-1D01*
G37*
G36*
G01X94099Y352800D02*
X93702Y353198D01*
Y371802D01*
X96302Y374402D01*
Y375698D01*
X96202Y375798D01*
Y426502D01*
X103498Y433798D01*
X107998D01*
X108199Y434000D01*
X112000D01*
X113500Y432500D01*
Y429499D01*
X112798Y428798D01*
Y376202D01*
X113500Y375501D01*
Y375500D01*
X116000Y373000D01*
Y353699D01*
X115101Y352800D01*
X94099D01*
G37*
G36*
G01X186702Y443500D02*
Y443902D01*
X177702D01*
Y444002D01*
X131498D01*
X128500Y447000D01*
Y476000D01*
X131000Y478500D01*
X139691D01*
X139705Y478316D01*
G03X140894Y476481I2295J184D01*
G01X140919Y476467D01*
X143088Y474298D01*
X144237D01*
G03X145400Y473798I1163J1103D01*
G01X148000D01*
G03X149602Y475400I0J1602D01*
G01Y478000D01*
G03X149599Y478080I-1601J-20D01*
G02X149999Y478500I400J20D01*
G01X202000D01*
X203500Y477000D01*
Y445000D01*
X202000Y443500D01*
X186702D01*
G37*
G36*
G01X138155Y550957D02*
Y551670D01*
G03X138980Y553071I-777J1401D01*
G01Y554471D01*
G03X137379Y556072I-1601J0D01*
G01X135979D01*
G03X134378Y554471I0J-1601D01*
G01Y553071D01*
G03X135202Y551670I1602J-1D01*
G01Y550843D01*
G03X135302Y546135I1569J-2322D01*
G01Y545172D01*
G03X134478Y543771I778J-1400D01*
G01Y542371D01*
G03X134482Y542252I1601J-6D01*
G02X134083Y541822I-399J-30D01*
G01X133173D01*
X133146Y541831D01*
G03Y537411I-646J-2210D01*
G01X133173Y537420D01*
X135681D01*
X135704Y537414D01*
G03X136079Y537370I373J1557D01*
G01X136483D01*
X137854Y535998D01*
X146002D01*
X148899Y533101D01*
X148898Y533018D01*
G03X150871Y530475I2602J-18D01*
G01X150925Y530462D01*
X151138Y530248D01*
X153000D01*
Y528500D01*
X151600Y527100D01*
X99500D01*
X98250Y528350D01*
Y529119D01*
X98267Y529157D01*
G03X98402Y529800I-1467J644D01*
G01Y531200D01*
G03X98051Y532200I-1602J-1D01*
G03X98402Y533200I-1251J1001D01*
G01Y534600D01*
G03X98357Y534975I-1602J-2D01*
G01X98352Y534998D01*
Y536322D01*
X98368Y536360D01*
G03X98502Y537000I-1468J641D01*
G01Y538600D01*
G03X98368Y539240I-1602J-1D01*
G01X98351Y539278D01*
Y539438D01*
X98434Y539498D01*
G03X99354Y542466I-1534J2102D01*
G02X99740Y542999I377J133D01*
G03X102033Y544264I60J2601D01*
G02X102659Y544341I343J-206D01*
G01X103500Y543500D01*
X108500D01*
X112000Y547000D01*
Y549145D01*
G03X112616Y550178I-1600J1655D01*
G01X112657Y550324D01*
X113534D01*
G03X113591Y553342I1766J1476D01*
G01X113532Y553276D01*
X113212D01*
X111052Y555437D01*
Y561500D01*
X127000D01*
X127290Y561790D01*
X127305D01*
X131927Y566412D01*
G02X132609Y566165I283J-283D01*
G03X137267Y564820I2591J235D01*
G01X137327Y564898D01*
X137611D01*
X137666Y564787D01*
G03X139100Y563898I1434J712D01*
G01X141700D01*
G03X142745Y564287I-1J1602D01*
G01X142886Y564408D01*
X145428Y561866D01*
Y556928D01*
X143000Y554500D01*
Y544426D01*
X138940D01*
G03X138256Y545172I-1462J-654D01*
G01Y546145D01*
G03X138155Y550957I-1485J2376D01*
G37*
G36*
G01X143598Y576850D02*
Y573727D01*
G03X143444Y569808I1632J-2027D01*
G03X143221Y569515I1154J-1110D01*
G02X142642Y569395I-344J204D01*
G03X141700Y569702I-943J-1295D01*
G01X139100D01*
G03X137539Y568457I0J-1601D01*
G01X137503Y568302D01*
X136978D01*
X136921Y568351D01*
G03X135435Y568991I-1721J-1951D01*
G02X135188Y569673I36J399D01*
G01X138802Y573286D01*
Y574402D01*
X138850Y574450D01*
Y577550D01*
X139500Y578200D01*
X142990D01*
X143001Y578011D01*
G03X143598Y576850I1599J88D01*
G37*
G36*
G01X104924Y586012D02*
Y582680D01*
G03X103938Y581500I1414J-2184D01*
G01X99702D01*
Y582612D01*
X95266Y587047D01*
Y591500D01*
X98000D01*
X98305Y591805D01*
X98358Y591819D01*
G03X99517Y592978I-393J1552D01*
G01X99531Y593031D01*
X101841Y595341D01*
X101970Y595274D01*
G03X102700Y595098I730J1426D01*
G01X104300D01*
G03X104708Y595151I-1J1602D01*
G01X104819Y595181D01*
X105220Y594780D01*
X105209Y594684D01*
G03X105198Y594500I1591J-187D01*
G01Y592900D01*
G03X106800Y591298I1602J0D01*
G01X107024D01*
Y588112D01*
X104924Y586012D01*
G37*
G36*
G01X134398Y575110D02*
X125481Y566192D01*
X117307D01*
X117000Y566500D01*
Y571000D01*
X118892Y572892D01*
X118985Y572798D01*
X121627D01*
X121654Y572790D01*
G03Y577210I646J2210D01*
G01X121627Y577202D01*
X120809D01*
X119002Y579009D01*
Y583938D01*
X119013Y583970D01*
G03X119102Y584496I-1513J527D01*
G01Y585602D01*
X119824Y586324D01*
X119919Y586313D01*
G03X120100Y586302I188J1591D01*
G01X121500D01*
G03X122580Y586722I-1J1602D01*
G02X123120I270J-296D01*
G03X124200Y586302I1081J1182D01*
G01X125600D01*
G03X126081Y586376I0J1602D01*
G02X126600Y585975I120J-381D01*
G03X126598Y585896I1600J-80D01*
G01Y584496D01*
G03X126687Y583970I1602J1D01*
G01X126698Y583938D01*
Y581173D01*
X126690Y581146D01*
G03X131110I2210J-646D01*
G01X131102Y581173D01*
Y583938D01*
X131113Y583970D01*
G03X131202Y584496I-1513J527D01*
G01Y585896D01*
G03X131099Y586459I-1602J-2D01*
G02X131474Y587000I374J141D01*
G01X132000D01*
X136500Y591500D01*
X137930D01*
G03X142886Y593761I2205J1729D01*
G01X142866Y593866D01*
X145059Y596059D01*
X145109Y596074D01*
G03X145142Y601446I-780J2691D01*
G01X145000Y601490D01*
Y608526D01*
G02X145433Y608925I400J0D01*
G03X145565Y608920I127J1596D01*
G01X146629D01*
X148000Y607549D01*
Y606000D01*
X148314Y605686D01*
Y605520D01*
X148480D01*
X149000Y605000D01*
X154500D01*
X155000Y604500D01*
Y604000D01*
X155634Y603366D01*
Y602779D01*
G03X156334Y601455I1602J0D01*
G01Y596947D01*
X153388Y594002D01*
X145688D01*
X134398Y582712D01*
Y575110D01*
G37*
G36*
G01X114600Y672551D02*
G03X114248Y672765I-1001J-1250D01*
G02X114127Y673413I162J365D01*
G01X115213Y674500D01*
X129500D01*
X130875Y675875D01*
X130917Y675891D01*
G03X131805Y676692I-551J1504D01*
G01X134500D01*
Y673500D01*
X129500Y668500D01*
X122358D01*
X122348Y668501D01*
G03X121828I-260J-2589D01*
G01X121818Y668500D01*
X121588D01*
X121462Y668626D01*
X118427D01*
G03X118251Y668900I-1428J-724D01*
G03X118602Y669900I-1251J1001D01*
G01Y671300D01*
G03X117000Y672902I-1602J0D01*
G01X115600D01*
G03X114600Y672551I1J-1602D01*
G37*
G36*
G01X122318Y718682D02*
X122304Y718709D01*
G03X121209Y719804I-2304J-1209D01*
G01X121182Y719818D01*
X121000Y720000D01*
X120722D01*
X120696Y720007D01*
G03X119304I-696J-2507D01*
G01X119278Y720000D01*
X118500D01*
X115000Y723500D01*
Y726000D01*
X116000Y727000D01*
X120000D01*
X122500Y724500D01*
X132500D01*
X134000Y723000D01*
Y717500D01*
X137000Y714500D01*
X138500D01*
X138750Y714250D01*
Y705750D01*
X138000Y705000D01*
X127500D01*
X126500Y706000D01*
Y714500D01*
X122318Y718682D01*
G37*
G36*
G01X88400Y724800D02*
Y731922D01*
G03X88602Y732700I-1400J779D01*
G01Y734100D01*
G03X88400Y734878I-1602J-1D01*
G01Y815900D01*
X89000Y816500D01*
X107000D01*
X110900Y812600D01*
Y792598D01*
G03Y792402I2600J-98D01*
G01Y713900D01*
X109000Y712000D01*
X91000D01*
X88400Y714600D01*
Y722200D01*
G03Y724800I-1900J1300D01*
G37*
G36*
G01X159024Y699612D02*
Y697999D01*
G02X158607Y697600I-400J1D01*
G03X158619Y692401I-107J-2600D01*
G01X158707Y692405D01*
X159206Y691906D01*
X159201Y691818D01*
G03X163437Y690456I2299J-118D01*
G02X164019Y690555I336J-216D01*
G03X166514Y694404I1414J1817D01*
G01X166500Y694418D01*
Y696901D01*
G02X166920Y697301I400J0D01*
G03X167000Y697298I100J1598D01*
G01X168400D01*
G03X169378Y697632I-1J1602D01*
G01X169432Y697673D01*
X169700D01*
Y697400D01*
X175498Y691602D01*
Y688800D01*
X173699Y687000D01*
X161199D01*
X157498Y690702D01*
X152998D01*
X152845Y690855D01*
X152884Y690972D01*
G03X150018Y693899I-2184J728D01*
G02X149500Y694281I-118J382D01*
G01Y694500D01*
X146000Y698000D01*
X141199D01*
X140000Y699199D01*
Y704901D01*
X140102Y705002D01*
Y714998D01*
X140000Y715099D01*
Y716500D01*
X139500Y717000D01*
X136500D01*
X135500Y718000D01*
Y722500D01*
X137000Y724000D01*
X144860D01*
G03X147140I1140J2000D01*
G01X151000D01*
X151098Y724098D01*
X152798D01*
X154752Y726052D01*
Y735252D01*
X155000Y735500D01*
X159038D01*
Y728102D01*
X159598D01*
X160000Y727700D01*
X164400D01*
X164802Y728102D01*
X165402D01*
Y735298D01*
X166702D01*
X166718Y735282D01*
Y728102D01*
X167000D01*
Y724500D01*
X165950Y723450D01*
X163250D01*
X154800Y715000D01*
X150500D01*
X149502Y714002D01*
X148800D01*
G03X147484Y713313I0J-1601D01*
G01X147424Y713226D01*
X147145D01*
X147085Y713307D01*
G03Y710193I-2085J-1557D01*
G01X147145Y710274D01*
X147368D01*
X147427Y710176D01*
G03X148800Y709398I1374J824D01*
G01X149763D01*
X150534Y708628D01*
X151000D01*
Y706594D01*
X150991Y706565D01*
G03X150891Y705968I2201J-676D01*
G01X150889Y705889D01*
X150202Y705202D01*
X149700D01*
G03X148964Y705022I2J-1602D01*
G01X148921Y705000D01*
X148500D01*
X148452Y704952D01*
X148222D01*
X148175Y704980D01*
G03X145894Y700981I-1175J-1980D01*
G01X145919Y700967D01*
X146338Y700548D01*
X149022D01*
X149060Y700532D01*
G03X149700Y700398I641J1468D01*
G01X151300D01*
G03X152411Y700847I-1J1602D01*
G02X152689I139J-144D01*
G03X153800Y700398I1112J1153D01*
G01X155200D01*
G03X156240Y700782I-1J1602D01*
G02X156760I260J-304D01*
G03X157800Y700398I1041J1218D01*
G01X159200D01*
G03X159318Y700403I-9J1602D01*
G01X159409Y700410D01*
X159615Y700203D01*
X159024Y699612D01*
G37*
G36*
G01X173041Y655277D02*
G03X171525Y652527I1059J-2377D01*
G01X171539Y652427D01*
X170612Y651500D01*
X167500D01*
X164000Y648000D01*
Y641500D01*
X156000D01*
X155000Y642500D01*
Y651321D01*
G03Y655079I-1800J1879D01*
G01Y665500D01*
X157098Y667598D01*
X161488D01*
X173161Y655925D01*
G02X173041Y655277I-283J-283D01*
G37*
%LPC*%
G75*
G36*
G01X144736Y1009123D02*
G02X145485Y1006060I-1636J-2023D01*
G03X145851Y1005500I367J-160D01*
G01X151335D01*
G02X151400Y1005502I82J-1599D01*
G01X152800D01*
G02X152865Y1005500I-17J-1601D01*
G01X155000D01*
X160521Y999979D01*
G02X160634Y999952I-318J-1580D01*
G01X162402D01*
X162425Y999957D01*
G02X162800Y1000002I377J-1557D01*
G01X164200D01*
G02X164575Y999957I-2J-1602D01*
G01X164598Y999952D01*
X166162D01*
X170202Y995912D01*
Y950088D01*
X163662Y943548D01*
X158098D01*
X158075Y943543D01*
G02X157700Y943498I-377J1557D01*
G01X156300D01*
G02X155925Y943543I2J1602D01*
G01X155902Y943548D01*
X154098D01*
X154075Y943543D01*
G02X153700Y943498I-377J1557D01*
G01X152300D01*
G02X151925Y943543I2J1602D01*
G01X151902Y943548D01*
X150098D01*
X150075Y943543D01*
G02X149700Y943498I-377J1557D01*
G01X148300D01*
G02X147925Y943543I2J1602D01*
G01X147902Y943548D01*
X147202D01*
Y935288D01*
X142212Y930298D01*
X130394D01*
X126588Y934104D01*
X124304D01*
X123498Y933298D01*
X115498D01*
X107702Y925502D01*
Y922674D01*
X103126Y918098D01*
X86374D01*
X77198Y927274D01*
Y927290D01*
X76790Y927698D01*
X76774D01*
X75775Y928698D01*
X41000D01*
G02Y935100I0J3201D01*
G01X78427D01*
X79426Y934102D01*
X79442D01*
X83602Y929942D01*
Y929926D01*
X89026Y924502D01*
X100474D01*
X101298Y925326D01*
Y926002D01*
X100298Y927002D01*
Y934998D01*
X100548Y935248D01*
Y936298D01*
X93502D01*
X90798Y939002D01*
Y941502D01*
X89502Y942798D01*
X84298D01*
X83000Y941500D01*
X59500D01*
X59002Y941998D01*
X58902D01*
X57298Y943602D01*
Y968702D01*
X57000Y969000D01*
X55500D01*
X54300Y970200D01*
X51500D01*
X50701Y970999D01*
X50650Y971014D01*
G02X51500Y977302I850J3087D01*
G01X53902D01*
X54000Y977400D01*
Y980000D01*
X54198Y980198D01*
Y981200D01*
G02X55800Y982802I1602J0D01*
G01X56302D01*
X57500Y984000D01*
X68565D01*
G02X69500Y984302I936J-1300D01*
G01X72100D01*
G02X72987Y984033I-1J-1602D01*
G01X73037Y984000D01*
X73500D01*
Y988500D01*
X74500Y989500D01*
X75235D01*
G02X75300Y989502I82J-1599D01*
G01X77900D01*
G02X77965Y989500I-17J-1601D01*
G01X88446D01*
G02X93142Y987855I2096J-1542D01*
G01X93139Y987768D01*
X95705Y985202D01*
X95800D01*
G02X97402Y983600I0J-1602D01*
G01Y982598D01*
X97500Y982500D01*
X101422D01*
G02X102200Y982702I779J-1400D01*
G01X104800D01*
G02X105359Y982601I-1J-1602D01*
G01X105480Y982556D01*
X105712Y982788D01*
X105332Y983168D01*
X105288Y983183D01*
G02X104198Y984700I511J1517D01*
G01Y987300D01*
G02X104467Y988187I1602J-1D01*
G01X104500Y988237D01*
Y988563D01*
X104467Y988613D01*
G02X104198Y989500I1333J888D01*
G01Y992100D01*
G02X105800Y993702I1602J0D01*
G01X108400D01*
G02X109724Y993002I0J-1602D01*
G01X111502D01*
X113500Y995000D01*
Y995710D01*
X113389Y995765D01*
G02X112924Y996113I711J1435D01*
G03X112333Y996109I-294J-272D01*
G02X112294Y999634I-1933J1741D01*
G03X112888Y999647I291J274D01*
G02X114100Y1000202I1212J-1046D01*
G01X115500D01*
G02X115977Y1000129I-1J-1602D01*
G01X116093Y1000093D01*
X116500Y1000500D01*
Y1006000D01*
X119000Y1008500D01*
X121500D01*
X122931Y1007069D01*
X138286Y1022424D01*
X140901D01*
G03X141300Y1022808I-1J400D01*
G02X146043Y1024176I2600J-108D01*
G01X146688D01*
X150452Y1020413D01*
Y1015463D01*
X144705Y1009717D01*
G03X144736Y1009123I283J-283D01*
G37*
G36*
G01X100500Y1263000D02*
X104500Y1267000D01*
X119000D01*
X122000Y1264000D01*
Y1255000D01*
X119500Y1252500D01*
X104000D01*
X100500Y1256000D01*
Y1263000D01*
G37*
G36*
G01X14369Y1694748D02*
X12098D01*
Y1703652D01*
X12572D01*
Y1703960D01*
X12481Y1704019D01*
G02X15009Y1708554I1419J2181D01*
G01X15136Y1708494D01*
X15377Y1708735D01*
X15224Y1708888D01*
Y1717485D01*
X16580Y1718841D01*
X16464Y1718981D01*
G02X16098Y1720000I1236J1019D01*
G01Y1721400D01*
G02X16874Y1722772I1601J0D01*
G01Y1745301D01*
X27853Y1756280D01*
X27811Y1756399D01*
G02X35001Y1757585I3488J1239D01*
G01X34999Y1757501D01*
X36700Y1755800D01*
Y1734325D01*
X36976Y1734049D01*
Y1711390D01*
X35510Y1709924D01*
X35524Y1709824D01*
G02X32576Y1706876I-2575J-373D01*
G01X32476Y1706890D01*
X31860Y1706274D01*
X26118D01*
Y1703652D01*
X30502D01*
Y1694748D01*
X27687D01*
X25902Y1692963D01*
Y1692100D01*
G02X24300Y1690498I-1602J0D01*
G01X22900D01*
G02X21900Y1690849I1J1602D01*
G02X20900Y1690498I-1001J1251D01*
G01X19500D01*
G02X18974Y1690587I1J1602D01*
G01X18942Y1690598D01*
X17412D01*
X15333Y1688519D01*
X15319Y1688494D01*
G02X12194Y1691619I-2019J1106D01*
G01X12219Y1691633D01*
X14652Y1694066D01*
G03X14369Y1694748I-283J282D01*
G37*
G36*
G01X11378Y1646598D02*
X11173D01*
X11146Y1646590D01*
G02Y1651010I-646J2210D01*
G01X11173Y1651002D01*
X13188D01*
X13998Y1651812D01*
Y1652648D01*
X12498D01*
Y1661552D01*
X16477D01*
G03X16846Y1662104I-1J400D01*
G02X19623Y1665675I2404J996D01*
G01X19723Y1665661D01*
X19788Y1665726D01*
X30828D01*
G02X32200Y1666502I1372J-825D01*
G01X33600D01*
G02X35202Y1664900I0J-1602D01*
G01Y1664037D01*
X39476Y1659762D01*
Y1653524D01*
X39500Y1653500D01*
Y1636000D01*
X36000Y1632500D01*
Y1621948D01*
X36050Y1621858D01*
Y1612604D01*
X34745Y1611299D01*
X34787Y1611180D01*
G02X32538Y1613429I-3488J-1239D01*
G01X32657Y1613387D01*
X33098Y1613828D01*
Y1616085D01*
G03X32561Y1616461I-400J0D01*
G02X27675Y1620697I-1262J3480D01*
G01X27697Y1620803D01*
X23000Y1625500D01*
Y1637162D01*
X22263Y1637898D01*
X21300D01*
G02X19698Y1639500I0J1602D01*
G01Y1640900D01*
G02X19800Y1641462I1602J0D01*
G03X19401Y1642002I-374J141D01*
G02X19300Y1641998I-114J1597D01*
G01X17900D01*
G02X17374Y1642087I1J1602D01*
G01X17342Y1642098D01*
X13973D01*
X13946Y1642090D01*
G02X11662Y1645917I-646J2210D01*
G03X11378Y1646598I-284J281D01*
G37*
G36*
G01X17000Y1451512D02*
Y1452818D01*
G03X16537Y1453213I-400J0D01*
G02Y1461117I-631J3952D01*
G03X17000Y1461512I63J395D01*
G01Y1462818D01*
G03X16537Y1463213I-400J0D01*
G02X13403Y1470288I-631J3952D01*
G03X13153Y1471000I-250J312D01*
G01X10500D01*
X10202Y1471298D01*
X10002D01*
X7298Y1474002D01*
Y1480998D01*
X7500Y1481199D01*
Y1482500D01*
X8500Y1483500D01*
X12954D01*
G03X13222Y1484197I0J400D01*
G02X18590I2684J2968D01*
G03X18858Y1483500I268J-297D01*
G01X27000D01*
X32000Y1478500D01*
Y1435000D01*
X37500Y1429500D01*
Y1427246D01*
X37517Y1427207D01*
G02X31819Y1415776I-7596J-3349D01*
G01X31763Y1415763D01*
X31000Y1415000D01*
X24500D01*
X23500Y1414000D01*
Y1393500D01*
X74500Y1342500D01*
Y1342199D01*
X74502Y1342198D01*
Y1206498D01*
X117000Y1164000D01*
X129000D01*
X134000Y1159000D01*
Y1143000D01*
X137000Y1140000D01*
X158000D01*
X160000Y1138000D01*
Y1117000D01*
X157000Y1114000D01*
X145665D01*
G02X145600Y1113998I-82J1599D01*
G01X143000D01*
G02X142935Y1114000I17J1601D01*
G01X104000D01*
X102000Y1112000D01*
Y1060951D01*
G02X102602Y1059700I-999J-1251D01*
G01Y1057100D01*
G02X102209Y1056050I-1602J1D01*
G02X102602Y1055000I-1209J-1051D01*
G01Y1052400D01*
G02X102000Y1051149I-1601J0D01*
G01Y1006500D01*
X97000Y1001500D01*
X72000D01*
X71002Y1000502D01*
Y999100D01*
G02X69400Y997498I-1602J0D01*
G01X68000D01*
G02X67935Y997500I17J1601D01*
G01X67102D01*
Y997200D01*
G02X66701Y996141I-1602J1D01*
G03X67001Y995476I300J-265D01*
G01X95388D01*
X116588Y1016676D01*
X125434D01*
G02Y1013724I1766J-1476D01*
G01X117812D01*
X96612Y992524D01*
X40712D01*
X40261Y992073D01*
X40275Y991973D01*
G02X38073Y994175I-2575J-373D01*
G01X38173Y994161D01*
X39488Y995476D01*
X51371D01*
G03X51760Y995969I0J400D01*
G02X55766Y997976I2240J531D01*
G01X61298D01*
Y999800D01*
G02X61922Y1001068I1602J-1D01*
G01X62000Y1001128D01*
Y1001472D01*
X61922Y1001532D01*
G02X61542Y1001950I977J1270D01*
G01X61530Y1001970D01*
X59500Y1004000D01*
Y1007000D01*
X57652Y1008848D01*
X56198D01*
Y1010302D01*
X56176Y1010324D01*
X54438D01*
X54262Y1010500D01*
X48000D01*
X43000Y1015500D01*
Y1018798D01*
X34548D01*
Y1020298D01*
X32488D01*
X31025Y1021762D01*
X30971Y1021775D01*
G02X34125Y1024929I629J2525D01*
G01X34138Y1024875D01*
X34207Y1024806D01*
G03X34548Y1024948I141J142D01*
G01Y1026202D01*
X43000D01*
Y1029798D01*
X34548D01*
Y1037202D01*
X35631D01*
G03X35914Y1037884I0J400D01*
G01X32657Y1041141D01*
X32538Y1041099D01*
G02X29708Y1047930I-1239J3489D01*
G01X29822Y1047984D01*
Y1048314D01*
X21174Y1056963D01*
Y1090382D01*
X20916D01*
Y1095784D01*
X22892D01*
Y1099955D01*
G02X22483Y1103644I1608J2045D01*
G03X22458Y1104177I-310J253D01*
G02X21998Y1105300I1141J1123D01*
G01Y1106700D01*
G02X23600Y1108302I1602J0D01*
G01X25000D01*
G02X26000Y1107951I-1J-1602D01*
G02X27000Y1108302I1001J-1251D01*
G01X28400D01*
G02X28926Y1108213I-1J-1602D01*
G01X28958Y1108202D01*
X38298D01*
G02X37637Y1103798I1002J-2402D01*
G01X28958D01*
X28926Y1103787D01*
G02X28400Y1103698I-527J1513D01*
G01X27000D01*
G02X26879Y1103703I6J1602D01*
G03X26696Y1103396I-15J-199D01*
G02X25844Y1099772I-2196J-1396D01*
G01Y1095784D01*
X27820D01*
Y1090382D01*
X24126D01*
Y1077529D01*
G03X24809Y1077246I400J0D01*
G01X28574Y1081011D01*
Y1081528D01*
G02X27798Y1082900I825J1372D01*
G01Y1084300D01*
G02X29400Y1085902I1602J0D01*
G01X30800D01*
G02X32402Y1084300I0J-1602D01*
G01Y1082900D01*
G02X31526Y1081473I-1602J1D01*
G01Y1079787D01*
X25876Y1074137D01*
Y1058912D01*
X27862Y1056926D01*
G03X28452Y1056953I283J283D01*
G02X32180Y1050991I2847J-2366D01*
G03X31993Y1050320I96J-388D01*
G01X32776Y1049538D01*
Y1047982D01*
G02X34787Y1043348I-1477J-3394D01*
G01X34745Y1043229D01*
X40476Y1037498D01*
Y1037202D01*
X43000D01*
Y1082797D01*
G03X42317Y1083079I-400J-1D01*
G01X32776Y1073537D01*
Y1067982D01*
G02X29822I-1477J-3395D01*
G01Y1074761D01*
X39974Y1084912D01*
Y1089863D01*
G03X39257Y1090107I-400J-1D01*
G02X36827Y1089125I-2057J1593D01*
G01X36727Y1089139D01*
X35320Y1087731D01*
Y1086506D01*
X28416D01*
Y1091910D01*
X34601D01*
X34626Y1092080D01*
G02X35815Y1093902I2574J-381D01*
G03X35941Y1094453I-213J339D01*
G02X35698Y1095300I1359J848D01*
G01Y1096700D01*
G02X35987Y1097617I1602J-1D01*
G03X35931Y1098138I-328J228D01*
G02X39209Y1101365I1569J1684D01*
G01X39268Y1101300D01*
X39289D01*
X42298Y1098291D01*
X42361Y1098280D01*
G02X42500Y1098251I-257J-1581D01*
G03X43000Y1098638I100J387D01*
G01Y1167412D01*
X27912Y1182500D01*
X11500D01*
X6500Y1187500D01*
Y1223500D01*
X7500Y1224500D01*
X12231D01*
G03X12565Y1225120I0J400D01*
G02X19247I3341J2203D01*
G03X19581Y1224500I334J-220D01*
G01X26000D01*
X39500Y1211000D01*
Y1195500D01*
X59500Y1175500D01*
Y1172000D01*
X60500Y1171000D01*
X62000D01*
X64500Y1173500D01*
Y1193500D01*
X60000Y1198000D01*
Y1199101D01*
X59998Y1199102D01*
Y1333502D01*
X9500Y1384000D01*
Y1384501D01*
X9298Y1384702D01*
Y1436698D01*
X15195Y1442594D01*
G03X15002Y1443266I-283J282D01*
G02X16537Y1451117I904J3899D01*
G03X17000Y1451512I63J395D01*
G37*
G36*
G01X69706Y823498D02*
X52295D01*
X51094Y824699D01*
X51021Y824705D01*
G02X53495Y827179I179J2295D01*
G01X53501Y827106D01*
X53705Y826902D01*
X58717D01*
G03X59085Y827457I0J400D01*
G02X62758Y830052I2122J894D01*
G01X99505D01*
X99509Y830048D01*
X100307D01*
G03X100685Y830577I0J400D01*
G02X100598Y831096I1505J519D01*
G01Y832496D01*
G02X101576Y833971I1601J0D01*
G01X101698Y834023D01*
Y836331D01*
G02X100798Y838300I1702J1968D01*
G03X100384Y838700I-400J0D01*
G02X98923Y842845I-84J2300D01*
G01Y845000D01*
X95106D01*
X92505Y842398D01*
X89346D01*
G02X88096Y841798I-1250J1002D01*
G01X86696D01*
G02X85696Y842149I1J1602D01*
G02X84696Y841798I-1001J1251D01*
G01X83296D01*
G02X82770Y841887I1J1602D01*
G01X82738Y841898D01*
X56988D01*
X56419Y842467D01*
X56394Y842481D01*
G02X58933Y846302I1107J2019D01*
G01X81744D01*
Y847402D01*
X81739Y847425D01*
G02X81694Y847800I1557J377D01*
G01Y849200D01*
G02X81739Y849575I1602J-2D01*
G01X81744Y849598D01*
Y851802D01*
X81739Y851825D01*
G02X81694Y852200I1557J377D01*
G01Y853600D01*
G02X81743Y853989I1601J-4D01*
G01X81748Y854013D01*
Y856102D01*
X81743Y856125D01*
G02X81698Y856500I1557J377D01*
G01Y857900D01*
G02X81743Y858275I1602J-2D01*
G01X81748Y858298D01*
Y860402D01*
X81743Y860425D01*
G02X81698Y860800I1557J377D01*
G01Y862200D01*
G02X81743Y862575I1602J-2D01*
G01X81748Y862598D01*
Y864602D01*
X81743Y864625D01*
G02X81698Y865000I1557J377D01*
G01Y866400D01*
G02X81743Y866775I1602J-2D01*
G01X81748Y866798D01*
Y870016D01*
X82000Y870267D01*
Y873000D01*
X85000Y876000D01*
X94500D01*
X96158Y877658D01*
X96171Y877712D01*
G02X99670Y879514I2529J-612D01*
G01X99706Y879500D01*
X100066D01*
G03X100432Y880060I-1J400D01*
G02X100298Y880700I1468J641D01*
G01Y882100D01*
G02X100385Y882619I1592J0D01*
G03X100007Y883148I-378J129D01*
G01X70455D01*
X68305Y880998D01*
X66151D01*
G02X62303Y882543I-1551J1702D01*
G03X61859Y882913I-399J-27D01*
G02X59306Y885390I-259J2287D01*
G03X58907Y885824I-399J34D01*
G01X58701D01*
G03X58301Y885435I0J-400D01*
G02X56450Y883243I-2301J65D01*
G03X56246Y882567I79J-392D01*
G01X56781Y882033D01*
X56806Y882019D01*
G02X53668Y878919I-1106J-2019D01*
G01X52488Y880098D01*
X45448D01*
Y887488D01*
X42530Y890406D01*
X42465Y890416D01*
G02X41098Y892000I234J1584D01*
G01Y893400D01*
G02X41449Y894400I1602J-1D01*
G02X41273Y894674I1252J998D01*
G01X38454D01*
X32657Y900471D01*
X32538Y900429D01*
G02X34787Y902678I-1239J3488D01*
G01X34745Y902559D01*
X39678Y897626D01*
X41328D01*
G02X42700Y898402I1372J-825D01*
G01X44100D01*
G03X44500Y898801I0J400D01*
G01Y902500D01*
X58500Y916500D01*
Y917512D01*
X57988Y918024D01*
X48032D01*
G03X47646Y917519I0J-400D01*
G02X47702Y917100I-1546J-420D01*
G01Y915700D01*
G02X46100Y914098I-1602J0D01*
G01X44700D01*
G02X43299Y914924I0J1601D01*
G01X35356D01*
G03X34960Y914464I0J-400D01*
G02X32538Y917405I-3661J-547D01*
G01X32657Y917363D01*
X33170Y917876D01*
X34286D01*
G03X34569Y918559I0J400D01*
G01X32657Y920471D01*
X32538Y920429D01*
G02X34787Y922678I-1239J3488D01*
G01X34745Y922559D01*
X36328Y920976D01*
X59212D01*
X65117Y915071D01*
X65172Y915058D01*
G02X66402Y913500I-372J-1558D01*
G01Y912687D01*
X76027Y903061D01*
X76127Y903075D01*
G02X79025Y901128I373J-2575D01*
G01X79063Y900976D01*
X145243D01*
X145284Y901122D01*
G02X149594Y899543I2216J-622D01*
G03X149957Y898976I364J-167D01*
G01X155715D01*
G02X156620Y896024I2085J-976D01*
G01X73112D01*
X68872Y891784D01*
G03X69155Y891102I283J-282D01*
G01X111405D01*
X115955Y886552D01*
X117392D01*
G02X118600Y887102I1208J-1052D01*
G01X120000D01*
G02X121602Y885500I0J-1602D01*
G01Y884100D01*
G02X121251Y883100I-1602J1D01*
G02X121602Y882100I-1251J-1001D01*
G01Y880700D01*
G02X120000Y879098I-1602J0D01*
G01X119884D01*
G03X119743Y878757I0J-200D01*
G01X120500Y878000D01*
Y855000D01*
X115522Y850022D01*
Y842102D01*
X115322D01*
Y840885D01*
X117409Y838797D01*
X117550Y838926D01*
G02X121302Y835337I1750J-1926D01*
G01Y833750D01*
G02X121902Y832500I-1002J-1250D01*
G01Y831100D01*
G02X121551Y830100I-1602J1D01*
G02X121902Y829100I-1251J-1001D01*
G01Y827700D01*
G02X120300Y826098I-1602J0D01*
G01X119305D01*
X117201Y823994D01*
X117195Y823921D01*
G02X114721Y826395I-2295J179D01*
G01X114794Y826401D01*
X117298Y828905D01*
Y829100D01*
G02X117649Y830100I1602J-1D01*
G02X117298Y831100I1251J1001D01*
G01Y832500D01*
G02X117421Y833115I1602J-1D01*
G03X117276Y833599I-369J153D01*
G02X117220Y833645I225J331D01*
G03X116100Y834102I-1120J-1144D01*
G01X114700D01*
G03X113580Y833645I0J-1601D01*
G02X113524Y833599I-281J285D01*
G03X113379Y833115I224J-331D01*
G02X113502Y832500I-1479J-616D01*
G01Y831100D01*
G02X113151Y830100I-1602J1D01*
G02X113502Y829100I-1251J-1001D01*
G01Y827700D01*
G02X112010Y826102I-1602J0D01*
G03X111824Y825903I14J-199D01*
G01Y825212D01*
X111088Y824476D01*
X109732D01*
X108755Y823498D01*
X101594D01*
G03X101196Y823069I1J-400D01*
G02X97134Y821424I-2296J-169D01*
G01X74166D01*
G02X70104Y823069I-1766J1476D01*
G03X69706Y823498I-399J29D01*
G37*
G36*
G01X38133Y1772199D02*
X36810D01*
G03X36428Y1771679I0J-400D01*
G02X36502Y1771200I-1528J-481D01*
G01Y1768600D01*
G02X34900Y1766998I-1602J0D01*
G01X32300D01*
G02X31100Y1767540I1J1602D01*
G03X30500I-300J-265D01*
G02X29276Y1766999I-1200J1060D01*
G01Y1765988D01*
X27294Y1764006D01*
X27299Y1763918D01*
G02X25118Y1766099I-2299J-118D01*
G01X25206Y1766094D01*
X25808Y1766696D01*
G03X25760Y1767303I-282J283D01*
G02X25490Y1767551I941J1296D01*
G03X24950Y1767611I-302J-262D01*
G02X24000Y1767298I-951J1289D01*
G01X22600D01*
G02X20998Y1768900I0J1602D01*
G01Y1770300D01*
G02X22600Y1771902I1602J0D01*
G01X24000D01*
G02X24724Y1771728I-2J-1602D01*
G03X25264Y1771908I181J357D01*
G02X25499Y1772259I1436J-708D01*
G03X25199Y1772924I-300J265D01*
G01X22330D01*
G02X17519Y1774765I-2274J1265D01*
G01X17524Y1774787D01*
Y1778048D01*
X17398D01*
Y1783952D01*
X25302D01*
Y1782476D01*
X27016D01*
X28387Y1783848D01*
X28388D01*
X28774Y1784233D01*
Y1785573D01*
G02X27898Y1787000I726J1428D01*
G01Y1788600D01*
G02X29500Y1790202I1602J0D01*
G01X31100D01*
G02X31450Y1790163I-1J-1602D01*
G01X31557Y1790139D01*
X37175Y1795758D01*
X37269D01*
X49000Y1807488D01*
Y1866000D01*
X28476Y1886524D01*
X24124D01*
X23000Y1885400D01*
Y1884000D01*
X19880Y1880880D01*
X19889Y1880785D01*
G02X13785Y1877000I-3983J-391D01*
G01X11000D01*
X9000Y1879000D01*
Y1910000D01*
X8000Y1911000D01*
Y1916000D01*
X11500Y1919500D01*
X11532D01*
G03X11929Y1919945I0J400D01*
G02X19883I3977J449D01*
G03X20280Y1919500I397J-45D01*
G01X65278D01*
X65304Y1919507D01*
G02X66696I696J-2507D01*
G01X66722Y1919500D01*
X108500D01*
X111000Y1917000D01*
Y1898500D01*
X113000Y1896500D01*
X141500D01*
X145000Y1893000D01*
Y1876000D01*
X141000Y1872000D01*
X136500D01*
X132500Y1868000D01*
Y1786500D01*
X136000Y1783000D01*
X140500D01*
X143000Y1780500D01*
Y1777000D01*
X140500Y1774500D01*
X135500D01*
X132500Y1771500D01*
Y1677000D01*
X140000Y1669500D01*
X184500D01*
X186500Y1667500D01*
Y1616000D01*
X188500Y1614000D01*
Y1582500D01*
X181000Y1575000D01*
Y1569500D01*
X177000Y1565500D01*
Y1510222D01*
X177007Y1510196D01*
G02Y1508804I-2507J-696D01*
G01X177000Y1508778D01*
Y1504222D01*
X177007Y1504196D01*
G02Y1502804I-2507J-696D01*
G01X177000Y1502778D01*
Y1368500D01*
X173000Y1364500D01*
X159500D01*
X151000Y1373000D01*
Y1376000D01*
X148000Y1379000D01*
X115000D01*
X114976Y1379024D01*
X98888D01*
X96024Y1381888D01*
Y1391112D01*
X98388Y1393476D01*
X113000D01*
Y1394500D01*
X112500Y1395000D01*
X107000D01*
X106862Y1395138D01*
X103198D01*
Y1398802D01*
X102500Y1399500D01*
Y1406075D01*
G02X102322Y1406216I903J1323D01*
G03X101712Y1406131I-270J-296D01*
G02X101017Y1409614I-2212J1369D01*
G01X101069Y1409576D01*
X101999D01*
G02X102073Y1409697I1402J-774D01*
G01X102166Y1409834D01*
X94600Y1417400D01*
X88500D01*
X87000Y1418900D01*
Y1425137D01*
X86798Y1425338D01*
Y1427498D01*
X86790Y1427525D01*
G02X86976Y1429267I2210J645D01*
G01X87000Y1429312D01*
Y1429600D01*
X88900Y1431500D01*
X92000D01*
X92398Y1431898D01*
Y1432300D01*
G02X92489Y1432830I1602J-2D01*
G01X92500Y1432862D01*
Y1433538D01*
X92489Y1433570D01*
G02X92398Y1434100I1511J532D01*
G01Y1435700D01*
G02X92489Y1436230I1602J-2D01*
G01X92500Y1436262D01*
Y1436600D01*
X92363Y1436737D01*
X92262Y1436720D01*
G02X92000Y1436698I-265J1580D01*
G01X90600D01*
G02X90074Y1436787I1J1602D01*
G01X90042Y1436798D01*
X87288D01*
X86787Y1437300D01*
X86000D01*
X84550Y1438750D01*
Y1439950D01*
X84500Y1440000D01*
Y1441100D01*
X86000Y1442600D01*
X87102D01*
G02X87298I98J-2600D01*
G01X88800D01*
X89900Y1441500D01*
X92200D01*
X92420Y1441720D01*
X92409Y1441816D01*
G02X92398Y1442000I1591J187D01*
G01Y1443600D01*
G02X92489Y1444130I1602J-2D01*
G01X92500Y1444162D01*
Y1445238D01*
X92489Y1445270D01*
G02X92398Y1445800I1511J532D01*
G01Y1447200D01*
G02X92489Y1447730I1602J-2D01*
G01X92500Y1447762D01*
Y1448000D01*
X91802Y1448698D01*
X90600D01*
G02X89665Y1449000I1J1602D01*
G01X88564D01*
G02X84511Y1449969I-1664J2000D01*
G01X84496Y1450004D01*
X84000Y1450500D01*
Y1452500D01*
X84500Y1453000D01*
X85234D01*
X85289Y1453043D01*
G02X88564Y1453000I1611J-2043D01*
G01X89665D01*
G02X90600Y1453302I936J-1300D01*
G01X91302D01*
X91500Y1453500D01*
Y1457000D01*
X90500Y1458000D01*
X83000D01*
X82000Y1459000D01*
X80500D01*
Y1468000D01*
X81068Y1468568D01*
X81029Y1468685D01*
G02X82850Y1472019I2471J815D01*
G01X83000Y1472058D01*
Y1480500D01*
X81500Y1482000D01*
Y1489500D01*
X82048Y1490048D01*
Y1490162D01*
X82462Y1490575D01*
X82475Y1490629D01*
G02X84371Y1492525I2525J-629D01*
G01X84425Y1492538D01*
X85889Y1494002D01*
X97502D01*
X101000Y1497500D01*
Y1504500D01*
X99000Y1506500D01*
X53800D01*
X48300Y1512000D01*
Y1581583D01*
G02Y1584017I2300J1217D01*
G01Y1588083D01*
G02Y1590517I2300J1217D01*
G01Y1594083D01*
G02Y1596517I2300J1217D01*
G01Y1600083D01*
G02Y1602517I2300J1217D01*
G01Y1637300D01*
X48500Y1637500D01*
Y1741500D01*
X59250Y1752250D01*
Y1768750D01*
X54750Y1773250D01*
X54500Y1773000D01*
X50326D01*
Y1772093D01*
X50479Y1772056D01*
G02X51702Y1770500I-378J-1556D01*
G01Y1769537D01*
X53637Y1767602D01*
X55600D01*
G02X57202Y1766000I0J-1602D01*
G01Y1763400D01*
G02X55600Y1761798I-1602J0D01*
G01X53000D01*
G02X51800Y1762340I1J1602D01*
G03X51200I-300J-265D01*
G02X50610Y1761919I-1201J1059D01*
G03X50499Y1761664I76J-185D01*
G02X50602Y1761100I-1499J-565D01*
G01Y1759500D01*
G02X49824Y1758127I-1602J1D01*
G01X49726Y1758068D01*
Y1757832D01*
X49824Y1757773D01*
G02X50602Y1756400I-824J-1374D01*
G01Y1755000D01*
G02X50251Y1754000I-1602J1D01*
G02X50602Y1753000I-1251J-1001D01*
G01Y1748287D01*
G02X46170Y1748241I-2202J-1387D01*
G01X46198Y1748288D01*
Y1748700D01*
X43802D01*
Y1748288D01*
X43830Y1748241D01*
G02X39370I-2230J-1341D01*
G01X39398Y1748288D01*
Y1748700D01*
X37400D01*
Y1770500D01*
X38416Y1771516D01*
G03X38133Y1772199I-283J283D01*
G37*
G36*
G01X26040Y259102D02*
X24770D01*
Y266004D01*
X25994D01*
Y267699D01*
G02X26126Y271375I1906J1772D01*
G03X26136Y271950I-273J292D01*
G01X25369Y272717D01*
X25344Y272731D01*
G02X28469Y275856I1106J2019D01*
G01X28483Y275831D01*
X29812Y274502D01*
X31542D01*
X31574Y274513D01*
G02X32100Y274602I527J-1513D01*
G01X33500D01*
G02X34500Y274251I-1J-1602D01*
G02X35500Y274602I1001J-1251D01*
G01X36900D01*
G02X38301Y273776I0J-1601D01*
G01X41634D01*
G02X45173Y270832I1766J-1476D01*
G03X45480Y270176I308J-256D01*
G01X47388D01*
X51888Y274676D01*
X51843Y274796D01*
G02X54884Y273474I2157J804D01*
G01X54847Y273459D01*
X48612Y267224D01*
X41227D01*
X40187Y266184D01*
G03X40470Y265502I283J-282D01*
G01X42036D01*
X46176Y261361D01*
Y250497D01*
G03X46861Y250217I400J1D01*
G02X50609Y247678I1639J-1617D01*
G03X50805Y247399I184J-79D01*
G02X50900Y247402I98J-1599D01*
G01X53500D01*
G02X55102Y245800I0J-1602D01*
G01Y243200D01*
G02X53500Y241598I-1602J0D01*
G01X50900D01*
G02X49850Y241991I1J1602D01*
G02X48800Y241598I-1051J1208D01*
G01X46196D01*
G02X45101Y242032I1J1601D01*
G03X44544Y242023I-274J-291D01*
G01X34745Y232224D01*
X34787Y232105D01*
G02X32538Y234354I-3488J-1239D01*
G01X32657Y234312D01*
X40111Y241766D01*
G03X39828Y242448I-283J282D01*
G01X34976D01*
Y241088D01*
X26976Y233088D01*
Y224812D01*
X28493Y223295D01*
X28636Y223437D01*
X28637Y223439D01*
G02X30356Y217286I2662J-2573D01*
G03X29972Y216616I-102J-387D01*
G01X32109Y214479D01*
X32164Y214465D01*
G02X28664Y213467I-866J-3599D01*
G01X28804Y213608D01*
X22274Y220138D01*
Y235362D01*
X26424Y239512D01*
Y242448D01*
X24198D01*
Y251602D01*
X20894D01*
Y258504D01*
X25963D01*
G02X26183Y258762I2086J-1556D01*
G03X26040Y259102I-143J140D01*
G37*
G36*
G01X74002Y51550D02*
Y54013D01*
G03X73402Y54360I-400J0D01*
G02X72602Y54146I-800J1388D01*
G01X71002D01*
G02X70544Y54213I0J1601D01*
G03X70288Y53997I-57J-192D01*
G02X70300Y53803I-1590J-196D01*
G01Y52403D01*
G02X68933Y50819I-1601J0D01*
G01X68868Y50809D01*
X68857Y50798D01*
X65173D01*
X65146Y50790D01*
G02X62552Y51774I-645J2210D01*
G03X61931Y51843I-338J-214D01*
G01X56721Y46634D01*
X19626D01*
G02Y49586I-3720J1476D01*
G01X55497D01*
X61637Y55726D01*
G03X61354Y56408I-283J282D01*
G01X19528D01*
G02Y59812I-3622J1702D01*
G01X62610D01*
X63349Y60550D01*
G03X63130Y61228I-283J283D01*
G02X62217Y65411I370J2272D01*
G03X62291Y66011I-223J332D01*
G02X64646Y69763I1709J1542D01*
G01X64673Y69754D01*
X64702D01*
G03X65101Y70184I0J400D01*
G02X65096Y70303I1597J127D01*
G01Y71266D01*
X61339Y75024D01*
X50653D01*
G03X50467Y74269I-1J-400D01*
G02X44021I-3223J-6159D01*
G03X43835Y75024I-185J355D01*
G01X42412D01*
X34022Y66634D01*
X19626D01*
G02X14229Y71744I-3720J1476D01*
G03X14278Y72075I-84J182D01*
G02X14057Y72298I1627J1834D01*
G01X10002D01*
X7798Y74502D01*
Y81998D01*
X10502Y84702D01*
X12693D01*
G03X12985Y85375I0J400D01*
G02X18323Y84920I2922J2735D01*
G03X18564Y84202I242J-318D01*
G01X27502D01*
X51552Y108252D01*
X51602D01*
X60252Y116902D01*
X73198D01*
X73400Y116699D01*
X73629Y116928D01*
X73590Y117045D01*
G02X88054Y117883I7119J2364D01*
G03X88445Y117402I391J-81D01*
G01X108998D01*
X120802Y105598D01*
Y59502D01*
X106698Y45398D01*
X85902D01*
X82198Y49102D01*
Y51550D01*
X74002D01*
G37*
G54D111*
X141300Y298100D03*
G54D107*
X15906Y481339D03*
Y491339D03*
Y521339D03*
Y771181D03*
G54D109*
X179606Y161889D03*
Y171889D03*
X169606Y161889D03*
Y171889D03*
X159606Y161889D03*
Y171889D03*
X149606Y161889D03*
Y171889D03*
X179606Y181889D03*
Y191889D03*
X169606Y181889D03*
Y191889D03*
X159606Y181889D03*
Y191889D03*
X149606Y181889D03*
Y191889D03*
X80709Y266929D03*
Y276929D03*
Y286929D03*
X110709Y266929D03*
X100709D03*
X90709D03*
X110709Y276929D03*
Y286929D03*
X100709Y276929D03*
Y286929D03*
X90709Y276929D03*
Y286929D03*
X179606Y256929D03*
Y266929D03*
X169606Y256929D03*
Y266929D03*
X159606Y256929D03*
Y266929D03*
X149606Y256929D03*
Y266929D03*
X179606Y276929D03*
Y286929D03*
X169606Y276929D03*
Y286929D03*
X159606Y276929D03*
Y286929D03*
X149606Y276929D03*
Y286929D03*
G54D108*
X150000Y64500D03*
X152500Y1906000D03*
G54D105*
X149606Y119409D03*
X80709Y329409D03*
X149606D03*
G54D103*
X80709Y139409D03*
X149606D03*
X80709Y309409D03*
X149606D03*
G54D104*
X47244Y1207323D03*
Y1467165D03*
Y501338D03*
G54D102*
X29921Y24803D03*
Y111417D03*
Y717874D03*
Y804488D03*
X30000Y1164000D03*
X29921Y1250630D03*
Y1510472D03*
Y1857086D03*
Y1943701D03*
G54D106*
X27559Y157480D03*
Y1811023D03*
X179134Y78740D03*
X179133Y570866D03*
X179134Y1161417D03*
Y1889764D03*
G54D110*
X178937Y1328740D03*
X161417Y1747835D03*
Y1823031D03*
%LPD*%
G75*
G36*
G01X10500Y73500D02*
X9000Y75000D01*
Y81500D01*
X11000Y83500D01*
X13000D01*
X13500Y83000D01*
X28000D01*
X52050Y107050D01*
X52100D01*
X60750Y115700D01*
X72700D01*
X78850Y109550D01*
X81550D01*
X82048Y109052D01*
Y107452D01*
X80298D01*
Y98548D01*
X82048D01*
Y81048D01*
X76000Y75000D01*
X68150D01*
X63500Y79650D01*
X39950D01*
X33800Y73500D01*
X10500D01*
G37*
G36*
G01X40013Y254727D02*
G02X39365Y254848I-283J283D01*
G03X37900Y255802I-1465J-648D01*
G01X36500D01*
G03X35122Y255016I0J-1601D01*
G02X34778I-172J102D01*
G03X34651Y255200I-1378J-816D01*
G03X35002Y256200I-1251J1001D01*
G01Y257600D01*
G03X33400Y259202I-1602J0D01*
G01X32000D01*
G03X31625Y259157I2J-1602D01*
G01X31602Y259152D01*
X30172D01*
Y262096D01*
G02X30854Y262380I400J0D01*
G03X31982Y261916I1127J1137D01*
G01X33382D01*
G03X34382Y262266I1J1601D01*
G03X35382Y261916I999J1251D01*
G01X36782D01*
G03X38057Y262548I0J1602D01*
G01X40812D01*
X43224Y260137D01*
Y256783D01*
G02X42776Y256385I-400J-1D01*
G03X40481Y255206I-276J-2285D01*
G01X40467Y255181D01*
X40013Y254727D01*
G37*
G36*
G01X51500Y1038000D02*
X49976Y1039524D01*
Y1171114D01*
X29500Y1191590D01*
Y1204500D01*
X21500Y1212500D01*
X10500D01*
X8000Y1215000D01*
Y1221000D01*
X10000Y1223000D01*
X23000D01*
X37000Y1209000D01*
Y1195000D01*
X58000Y1174000D01*
Y1096552D01*
X57998D01*
Y1084648D01*
X58000D01*
Y1083875D01*
X62500Y1079375D01*
X70625D01*
X71500Y1078500D01*
Y1074152D01*
X70698D01*
Y1065248D01*
X71500D01*
Y1038500D01*
X71000Y1038000D01*
X51500D01*
G37*
G36*
G01X22000Y1426343D02*
X21991Y1426314D01*
G03X22000Y1421374I7930J-2456D01*
G01Y1393000D01*
X73300Y1341700D01*
Y1205000D01*
X115900Y1162400D01*
X128600D01*
X132500Y1158500D01*
Y1143300D01*
X129900Y1140700D01*
X109552D01*
Y1140802D01*
X100648D01*
Y1140700D01*
X100000D01*
X97400Y1143300D01*
Y1150600D01*
X96000Y1152000D01*
Y1164800D01*
X91734Y1169066D01*
X91722Y1169086D01*
G03X90686Y1170122I-2722J-1686D01*
G01X90666Y1170134D01*
X61200Y1199600D01*
Y1334500D01*
X10500Y1385200D01*
Y1436200D01*
X18154Y1443854D01*
X18169Y1443864D01*
G03X18500Y1450212I-2263J3301D01*
G01Y1454118D01*
G03Y1460212I-2594J3047D01*
G01Y1464118D01*
G03X18567Y1470154I-2594J3047D01*
G01X18500Y1470214D01*
Y1470500D01*
X16500Y1472500D01*
X10500D01*
X8500Y1474500D01*
Y1480500D01*
X10000Y1482000D01*
X25000D01*
X30500Y1476500D01*
Y1436000D01*
X25155Y1430655D01*
X25141Y1430645D01*
G03X23134Y1428638I4780J-6787D01*
G01X23124Y1428624D01*
X22000Y1427500D01*
Y1426343D01*
G37*
G36*
G01X65617Y1918347D02*
G03X65650Y1918356I-300J1164D01*
G02X66350I350J-1356D01*
G03X66383Y1918347I333J1155D01*
G01X66409Y1918340D01*
G03X66749Y1918298I316J1160D01*
G01X107702D01*
X108500Y1917500D01*
Y1899000D01*
X106000Y1896500D01*
X84552D01*
Y1897202D01*
X75648D01*
Y1896500D01*
X67000D01*
X57000Y1906500D01*
X50565D01*
G03X43923I-3321J-6107D01*
G01X31000D01*
X28000Y1903500D01*
X18430D01*
G03X13382I-2524J-3106D01*
G01X10500D01*
X10202Y1903798D01*
Y1909975D01*
G03X9850Y1910850I-1202J25D01*
G01X9500Y1911200D01*
Y1912500D01*
X12000Y1915000D01*
X19000D01*
X22298Y1918298D01*
X65251D01*
G03X65591Y1918340I24J1202D01*
G01X65617Y1918347D01*
G37*
G36*
G01X41241Y1903898D02*
G03X53247I6003J-3505D01*
G02X53592Y1904500I345J202D01*
G01X56500D01*
X68000Y1893000D01*
Y1878500D01*
X63500Y1874000D01*
X52500D01*
X31500Y1895000D01*
X26000D01*
X25000Y1896000D01*
Y1899500D01*
X27000Y1901500D01*
X29500D01*
X32500Y1904500D01*
X40896D01*
G02X41241Y1903898I0J-400D01*
G37*
G36*
G01X119600Y60000D02*
X106629Y47029D01*
G03X102948Y46600I-1629J-2029D01*
G01X97052D01*
G03X92948I-2052J-1600D01*
G01X87052D01*
G03X85494Y47555I-2052J-1600D01*
G01X85434Y47566D01*
X83400Y49600D01*
Y52600D01*
X85069Y54269D01*
X85119Y54283D01*
G03X86717Y55881I-619J2217D01*
G01X86731Y55931D01*
X87300Y56500D01*
X94400D01*
X94900Y57000D01*
Y65548D01*
X99802D01*
Y71452D01*
X94900D01*
Y75500D01*
X84000D01*
X83794Y75706D01*
X83786Y75775D01*
G03X83500Y76640I-2286J-276D01*
G01Y78000D01*
X83250Y78250D01*
Y112351D01*
G03X87489Y116200I-2541J7058D01*
G01X108500D01*
X119600Y105100D01*
Y60000D01*
G37*
G36*
G01X76570Y57974D02*
X74076D01*
G03X72964Y58907I-1474J-627D01*
G02X72669Y59405I90J390D01*
G03X72664Y60677I-2215J627D01*
G01X72656Y60704D01*
Y61806D01*
G03X73002Y62800I-1255J994D01*
G01Y64200D01*
G03X71400Y65802I-1602J0D01*
G01X70000D01*
G03X69978Y65801I62J-1599D01*
G02X69598Y66342I-6J400D01*
G03X69700Y66903I-1500J562D01*
G01Y68303D01*
G03X69349Y69303I-1602J-1D01*
G03X69491Y69513I-1252J999D01*
G02X69769Y69585I174J-99D01*
G03X70600Y69352I832J1369D01*
G01X72200D01*
G03X72781Y69462I-2J1602D01*
G02X73026Y69378I73J-186D01*
G03X74400Y68598I1375J822D01*
G01X76313D01*
X77888Y67024D01*
X85796D01*
G02X86159Y66457I-1J-400D01*
G03X86076Y64752I2094J-956D01*
G02X85588Y64238I-378J-129D01*
G03X85147Y64300I-441J-1540D01*
G01X82547D01*
G03X81347Y63758I1J-1602D01*
G02X80747I-300J265D01*
G03X79547Y64300I-1201J-1060D01*
G01X76947D01*
G03X75346Y62698I0J-1601D01*
G01Y60098D01*
G03X76435Y58581I1601J0D01*
G01X76570Y58535D01*
Y57974D01*
G37*
G36*
G01X88065Y70461D02*
G03X88102Y70800I-1565J342D01*
G01Y72200D01*
G03X86500Y73802I-1602J0D01*
G01X85100D01*
G03X84386Y73634I0J-1601D01*
G02X83887Y73754I-178J358D01*
G03X83710Y73954I-1284J-958D01*
G02X83849Y74298I139J144D01*
G01X93698D01*
Y71452D01*
X91898D01*
Y69976D01*
X88456D01*
G02X88065Y70461I0J400D01*
G37*
G36*
G01X81904Y53769D02*
Y57454D01*
X79524D01*
Y58497D01*
G03X80747Y59038I23J1601D01*
G02X81347I300J-265D01*
G03X82547Y58496I1201J1060D01*
G01X85147D01*
G03X86550Y59325I0J1602D01*
G02X86822Y59404I175J-96D01*
G03X87603Y59200I782J1398D01*
G01X89003D01*
G03X90604Y60802I0J1601D01*
G01Y62202D01*
G03X90037Y63425I-1601J1D01*
G02X89993Y63993I258J306D01*
G03X90347Y66457I-1740J1507D01*
G02X90710Y67024I364J167D01*
G01X91898D01*
Y65548D01*
X93698D01*
Y57702D01*
X86802D01*
X82587Y53486D01*
G02X81904Y53769I-283J283D01*
G37*
G36*
G01X59400Y943200D02*
X58500Y944100D01*
Y969500D01*
X58798Y969798D01*
X70498D01*
X74399Y973700D01*
X79400D01*
X79550Y973550D01*
Y967404D01*
X79544Y967380D01*
G03X79498Y967000I1556J-381D01*
G01Y965398D01*
X72800Y958700D01*
Y944900D01*
X71100Y943200D01*
X59400D01*
G37*
G36*
G01X96500Y958000D02*
Y953722D01*
X96493Y953696D01*
G03Y952304I2507J-696D01*
G01X96500Y952278D01*
Y947500D01*
X99000Y945000D01*
X105912D01*
X108000Y942912D01*
Y938500D01*
X107302Y937802D01*
X100548D01*
Y937500D01*
X94000D01*
X92000Y939500D01*
Y942000D01*
X90000Y944000D01*
X84500D01*
X83500Y945000D01*
Y954000D01*
X88500Y959000D01*
X95500D01*
X96500Y958000D01*
G37*
G36*
G01X71002Y1005000D02*
G03X70500Y1006164I-1602J-1D01*
G01Y1014500D01*
X74000Y1018000D01*
Y1018875D01*
G03X74702Y1020200I-899J1325D01*
G01Y1021600D01*
G03X74000Y1022925I-1601J0D01*
G01Y1023449D01*
G03X74602Y1024700I-999J1251D01*
G01Y1026100D01*
G03X74000Y1027351I-1601J0D01*
G01Y1113200D01*
X72000Y1115200D01*
X63600D01*
X62300Y1116500D01*
Y1121200D01*
X62500Y1121400D01*
X65400D01*
X66500Y1122500D01*
Y1128600D01*
X67100Y1129200D01*
X73400D01*
X74200Y1128400D01*
Y1124700D01*
X74500Y1124400D01*
X79449D01*
G03X80696Y1123802I1248J1003D01*
G01X82100D01*
G03X83347Y1124400I-1J1601D01*
G01X84600D01*
X85100Y1124900D01*
Y1126500D01*
X85000Y1126600D01*
Y1129000D01*
X86650Y1130650D01*
X90450D01*
X98400Y1138600D01*
X100648D01*
Y1138198D01*
X109552D01*
Y1138600D01*
X157000D01*
X158500Y1137100D01*
Y1118700D01*
X155000Y1115200D01*
X101700D01*
X100000Y1113500D01*
Y1008000D01*
X94702Y1002702D01*
X72025D01*
G03X71438Y1002562I-24J-1202D01*
G01X70919Y1003081D01*
X70949Y1003192D01*
G03X71002Y1003600I-1549J409D01*
G01Y1005000D01*
G37*
G36*
G01X97000Y974665D02*
Y971000D01*
X96500Y970500D01*
X93000D01*
X92500Y971000D01*
Y974500D01*
X92000Y975000D01*
X85000D01*
Y974902D01*
X84798D01*
Y971298D01*
X84500Y971000D01*
X82500D01*
X82000Y971500D01*
Y980500D01*
X82500Y981000D01*
X84500D01*
X84798Y980702D01*
Y977698D01*
X85802D01*
X86000Y977500D01*
X91000D01*
X91198Y977698D01*
X91202D01*
Y977702D01*
X92000Y978500D01*
X96094D01*
X96545Y978048D01*
X96711D01*
G02X96887Y977754I0J-200D01*
G03X96698Y977000I1413J-755D01*
G01Y975600D01*
G03X97000Y974665I1602J1D01*
G37*
G36*
G01X55000Y975500D02*
X55357Y975857D01*
X55464Y975834D01*
G03X55800Y975798I338J1566D01*
G01X58400D01*
G03X59999Y977311I0J1601D01*
G01X60010Y977500D01*
X68500D01*
X69000Y978000D01*
X74198D01*
Y977698D01*
X79302D01*
X79500Y977500D01*
Y975000D01*
X74000D01*
X70000Y971000D01*
X68678D01*
G03X65122I-1778J-1900D01*
G01X55500D01*
X55000Y971500D01*
Y975500D01*
G37*
G36*
G01X72000Y1081500D02*
X63500D01*
X59500Y1085500D01*
Y1112000D01*
X61000Y1113500D01*
X70000D01*
X72798Y1110702D01*
Y1082298D01*
X72000Y1081500D01*
G37*
G36*
G01X69024Y1157476D02*
Y1146119D01*
G03X68798Y1145300I1376J-820D01*
G01Y1144237D01*
X68726Y1144164D01*
Y1142298D01*
X67250D01*
Y1140750D01*
X67000Y1140500D01*
X64962D01*
G03X63898Y1140904I-1063J-1197D01*
G01X62498D01*
G03X61600Y1140629I-1J-1601D01*
G01X61463Y1140537D01*
X59500Y1142500D01*
Y1155500D01*
X62000Y1158000D01*
X68500D01*
X69024Y1157476D01*
G37*
G36*
G01X110701Y1569673D02*
Y1571098D01*
X111202D01*
Y1578614D01*
X112052D01*
Y1578698D01*
X124948D01*
Y1578614D01*
X140798D01*
Y1571098D01*
X141298D01*
Y1568131D01*
X141292Y1568106D01*
G03Y1566934I2226J-586D01*
G01X141298Y1566909D01*
Y1566626D01*
X141485Y1566439D01*
X141499Y1566414D01*
G03X145711Y1568220I2019J1106D01*
G01X145702Y1568250D01*
Y1571098D01*
X146202D01*
Y1578614D01*
X147052D01*
Y1578698D01*
X158948D01*
Y1578614D01*
X174798D01*
Y1571098D01*
X175000D01*
Y1515000D01*
X175798Y1514202D01*
Y1510249D01*
G03X175840Y1509909I1202J-24D01*
G01X175847Y1509883D01*
G03X175856Y1509850I1164J300D01*
G02Y1509150I-1356J-350D01*
G03X175847Y1509117I1155J-333D01*
G01X175840Y1509091D01*
G03X175798Y1508751I1160J-316D01*
G01Y1504249D01*
G03X175840Y1503909I1202J-24D01*
G01X175847Y1503883D01*
G03X175856Y1503850I1164J300D01*
G02Y1503150I-1356J-350D01*
G03X175847Y1503117I1155J-333D01*
G01X175840Y1503091D01*
G03X175798Y1502751I1160J-316D01*
G01Y1488798D01*
X149609Y1462609D01*
X149533Y1462605D01*
G03X147281Y1461000I153J-2598D01*
G01X143000D01*
X142743Y1461257D01*
X142766Y1461364D01*
G03X142802Y1461700I-1566J338D01*
G01Y1463100D01*
G03X142500Y1464035I-1602J-1D01*
G01Y1464765D01*
G03X142802Y1465700I-1300J936D01*
G01Y1467100D01*
G03X142798Y1467202I-1602J-12D01*
G01X142792Y1467292D01*
X143500Y1468000D01*
X145000D01*
X146000Y1469000D01*
Y1471000D01*
X146948Y1471948D01*
X147122D01*
X147160Y1471932D01*
G03X147800Y1471798I641J1468D01*
G01X149200D01*
G03X150569Y1472569I0J1601D01*
G01X156000Y1478000D01*
Y1498500D01*
X155000Y1499500D01*
X149246D01*
G03X147775Y1500286I-1747J-1500D01*
G01X147706Y1500294D01*
X138000Y1510000D01*
X136498D01*
G03X133518I-1490J-1755D01*
G01X54500D01*
X49502Y1514998D01*
Y1577501D01*
X50699Y1578698D01*
X72698D01*
Y1572312D01*
X71288Y1570902D01*
X68373D01*
X68346Y1570910D01*
G03Y1566490I-646J-2210D01*
G01X68373Y1566498D01*
X73112D01*
X77602Y1570988D01*
Y1571198D01*
X78102D01*
Y1578698D01*
X89948D01*
Y1578614D01*
X105798D01*
Y1571098D01*
X106298D01*
Y1569673D01*
X106290Y1569646D01*
G03X110710I2210J-646D01*
G01X110701Y1569673D01*
G37*
G36*
G01X139020Y1625327D02*
X136848Y1623154D01*
X135050D01*
Y1619452D01*
X134748D01*
Y1617202D01*
X114902D01*
Y1617748D01*
X114949Y1617804D01*
G03X114845Y1620910I-1749J1496D01*
G02Y1621190I143J140D01*
G03X111704Y1624549I-1645J1610D01*
G01X111648Y1624502D01*
X111095D01*
X109748Y1623154D01*
X106550D01*
Y1619452D01*
X106248D01*
Y1617202D01*
X85014D01*
G03X84705Y1617600I-1962J-1204D01*
G02X84698Y1618148I288J278D01*
G03X82023Y1621787I-1698J1555D01*
G02X81454Y1622150I-169J362D01*
G01Y1623154D01*
X76050D01*
Y1619452D01*
X75748D01*
Y1617202D01*
X54799D01*
X52000Y1620000D01*
Y1742500D01*
X61000Y1751500D01*
Y1869000D01*
X63750Y1871750D01*
X119500D01*
X128000Y1863250D01*
Y1785500D01*
X125500Y1783000D01*
X117000D01*
X114500Y1780500D01*
Y1777000D01*
X117000Y1774500D01*
X126000D01*
X128000Y1772500D01*
Y1676500D01*
X137500Y1667000D01*
X181500D01*
X184000Y1664500D01*
Y1620500D01*
X180702Y1617201D01*
X171776D01*
G02X171494Y1617884I1J400D01*
G01X174702Y1621092D01*
Y1624714D01*
G03X171602Y1628104I-1432J1803D01*
G02X171331Y1628087I-145J138D01*
G03X168174Y1624752I-1455J-1784D01*
G01Y1623581D01*
X167748Y1623154D01*
X162550D01*
Y1619452D01*
X162248D01*
Y1617202D01*
X143002D01*
Y1619855D01*
G03X143092Y1623263I-1502J1745D01*
G02X143076Y1623535I138J145D01*
G03X139031Y1625389I-1776J1465D01*
G01X139020Y1625327D01*
G37*
G36*
G01X49362Y1582145D02*
G02Y1583455I1238J655D01*
G03X49502Y1584044I-1062J563D01*
G01Y1588056D01*
G03X49362Y1588645I-1202J26D01*
G02Y1589955I1238J655D01*
G03X49502Y1590544I-1062J563D01*
G01Y1594056D01*
G03X49362Y1594645I-1202J26D01*
G02Y1595955I1238J655D01*
G03X49502Y1596544I-1062J563D01*
G01Y1600056D01*
G03X49362Y1600645I-1202J26D01*
G02Y1601955I1238J655D01*
G03X49502Y1602544I-1062J563D01*
G01Y1610502D01*
X55000Y1616000D01*
X76050D01*
Y1615548D01*
X75748D01*
Y1613548D01*
X76050D01*
Y1609846D01*
X81454D01*
Y1613547D01*
X81904Y1613998D01*
X82033Y1613935D01*
G03X85345Y1615816I1017J2065D01*
G01X85359Y1616000D01*
X106550D01*
Y1615548D01*
X106248D01*
Y1613548D01*
X106550D01*
Y1609846D01*
X111954D01*
Y1614147D01*
X113806Y1616000D01*
X135050D01*
Y1615548D01*
X134748D01*
Y1613548D01*
X135050D01*
Y1609846D01*
X140454D01*
Y1614047D01*
X142406Y1616000D01*
X162550D01*
Y1615548D01*
X162248D01*
Y1613548D01*
X162550D01*
Y1609846D01*
X167954D01*
Y1614344D01*
X169609Y1616000D01*
X184500D01*
X187298Y1613202D01*
Y1583298D01*
X183900Y1579900D01*
X180202D01*
Y1579902D01*
X159798D01*
Y1579900D01*
X146202D01*
Y1579902D01*
X125798D01*
Y1579900D01*
X111202D01*
Y1579902D01*
X90798D01*
Y1579900D01*
X78102D01*
Y1580002D01*
X57698D01*
Y1579900D01*
X50000D01*
X49502Y1580398D01*
Y1581556D01*
G03X49362Y1582145I-1202J26D01*
G37*
G36*
G01X137702Y1895298D02*
X143798Y1889202D01*
Y1876798D01*
X143000Y1876000D01*
X70500D01*
X69000Y1877500D01*
Y1877801D01*
X69202Y1878002D01*
Y1892202D01*
X72298Y1895298D01*
X75648D01*
Y1894598D01*
X84552D01*
Y1895298D01*
X106498D01*
X106699Y1895500D01*
X112334D01*
G03X113025Y1895298I667J1000D01*
G01X137702D01*
G37*
G36*
G01X122371Y937454D02*
G03X123143Y937653I-1J1602D01*
G01X123275Y937725D01*
X123500Y937500D01*
Y935000D01*
X123000Y934500D01*
X115000D01*
X105500Y925000D01*
X104000D01*
X101500Y927500D01*
Y934500D01*
X102000Y935000D01*
X107000D01*
X107198Y935198D01*
X108452D01*
Y936452D01*
X109437Y937437D01*
X109538Y937420D01*
G03X109800Y937398I265J1580D01*
G01X111200D01*
G03X112676Y938378I0J1602D01*
G01X112727Y938500D01*
X115073D01*
X115124Y938378D01*
G03X116600Y937398I1476J622D01*
G01X118000D01*
G03X119209Y937950I-1J1602D01*
G02X119803Y937961I302J-263D01*
G03X120971Y937454I1169J1095D01*
G01X122371D01*
G37*
G36*
G01X132218Y934702D02*
X128412Y938508D01*
X124192D01*
X123947Y938753D01*
X123959Y938850D01*
G03X123972Y939056I-1588J204D01*
G01Y940456D01*
G03X122371Y942058I-1602J0D01*
G01X121530D01*
Y943457D01*
G03Y947743I-1476J2143D01*
G01Y952708D01*
X122265Y953442D01*
X123229D01*
G03X124830Y955044I0J1601D01*
G01Y956444D01*
G03X123229Y958046I-1602J0D01*
G01X122366D01*
X120982Y959429D01*
Y967202D01*
X112058D01*
Y958798D01*
X112484D01*
Y958046D01*
X111829D01*
G03X110457Y957270I0J-1601D01*
G01X109882D01*
X108673Y956061D01*
X108573Y956075D01*
G03X105625Y953127I-373J-2575D01*
G01X105639Y953027D01*
X104574Y951962D01*
Y946202D01*
X99498D01*
X97702Y947998D01*
Y955795D01*
X105202Y963295D01*
Y964531D01*
G03Y968469I-1702J1969D01*
G01Y971343D01*
X105335Y971390D01*
G03X106402Y972900I-535J1510D01*
G01Y975500D01*
G03X105860Y976700I-1602J-1D01*
G02Y977300I265J300D01*
G03X106402Y978500I-1060J1201D01*
G01Y981100D01*
G03X106401Y981127I-1600J-46D01*
G02X107084Y981416I400J6D01*
G01X110000Y978500D01*
Y977500D01*
X110500Y977000D01*
X123933D01*
X124298Y976634D01*
Y973088D01*
X128086Y969300D01*
X162914D01*
X165116Y971502D01*
G02X165798Y971219I282J-283D01*
G01Y951912D01*
X161838Y947952D01*
X159696D01*
G02X159297Y948381I0J400D01*
G03X159302Y948500I-1597J127D01*
G01Y949900D01*
G03X157700Y951502I-1602J0D01*
G01X156837D01*
X154775Y953563D01*
G03X154176Y954278I-2027J-1090D01*
G01Y955298D01*
X154602D01*
Y963702D01*
X135438D01*
Y960976D01*
X131388D01*
X131179Y960767D01*
X131088Y960773D01*
G03X128524Y957125I-185J-2595D01*
G01Y950388D01*
X129485Y949427D01*
X129409Y949294D01*
G03X129198Y948500I1391J-795D01*
G01Y947100D01*
G03X130800Y945498I1602J0D01*
G01X132200D01*
G03X133440Y946087I-1J1602D01*
G02X134060I310J-253D01*
G03X135300Y945498I1241J1013D01*
G01X136700D01*
G03X137940Y946087I-1J1602D01*
G02X138560I310J-253D01*
G03X139800Y945498I1241J1013D01*
G01X141200D01*
G03X142079Y945761I0J1602D01*
G02X142698Y945427I219J-334D01*
G01Y945100D01*
G03X142787Y944574I1602J1D01*
G01X142798Y944542D01*
Y937112D01*
X140388Y934702D01*
X132218D01*
G37*
G36*
G01X129112Y976798D02*
X130812Y978498D01*
X132100D01*
G03X133638Y979654I0J1601D01*
G01X133680Y979798D01*
X135000D01*
Y977500D01*
X135500Y977000D01*
X147800D01*
G02X148200Y976585I0J-400D01*
G03X149856Y974290I2300J-85D01*
G01X150000Y974248D01*
Y973704D01*
X129910D01*
X128702Y974912D01*
Y976798D01*
X129112D01*
G37*
G36*
G01X132502Y984257D02*
Y984665D01*
X132535Y984715D01*
G03X132802Y985600I-1335J885D01*
G01Y988200D01*
G03X131200Y989802I-1602J0D01*
G01X128600D01*
G03X126998Y988200I0J-1602D01*
G01Y985600D01*
G03X127963Y984130I1602J0D01*
G02X128143Y983551I-159J-367D01*
G03X127898Y982700I1357J-851D01*
G01Y981812D01*
X127288Y981202D01*
X125958D01*
X125622Y981538D01*
X123542D01*
Y989402D01*
X123116D01*
Y995578D01*
X123137Y995598D01*
X124000D01*
G03X125064Y996003I-1J1602D01*
G02X125613Y995987I266J-299D01*
G01X126000Y995600D01*
X134998D01*
Y992013D01*
X135000Y992012D01*
Y983402D01*
X133540D01*
G03X132635Y984210I-1440J-702D01*
G01X132502Y984257D01*
G37*
G36*
G01X113049Y1407087D02*
X112462Y1406500D01*
X106500D01*
X106263Y1406737D01*
X106306Y1406856D01*
G03X106402Y1407400I-1506J546D01*
G01Y1408800D01*
G03X106045Y1409808I-1602J0D01*
G01X106000Y1409863D01*
Y1410100D01*
X105000Y1411100D01*
X103900D01*
X103300Y1411700D01*
Y1421000D01*
X103781Y1421481D01*
X103892Y1421451D01*
G03X104300Y1421398I409J1549D01*
G01X105700D01*
G03X106108Y1421451I-1J1602D01*
G01X106219Y1421481D01*
X106700Y1421000D01*
Y1416100D01*
X107600Y1415200D01*
X112500D01*
X116600Y1419300D01*
Y1421600D01*
X116937Y1421937D01*
X117038Y1421920D01*
G03X117300Y1421898I265J1580D01*
G01X118700D01*
G03X119230Y1421989I-2J1602D01*
G01X119262Y1422000D01*
X119500D01*
X120000Y1421500D01*
Y1416500D01*
X113770Y1410270D01*
X113750Y1410258D01*
G03X112998Y1408900I850J-1358D01*
G01Y1407500D01*
G03X113028Y1407192I1602J1D01*
G01X113049Y1407087D01*
G37*
G36*
G01X100112Y1381976D02*
X98976Y1383112D01*
Y1389888D01*
X99612Y1390524D01*
X111500D01*
Y1382500D01*
X111682Y1382318D01*
G02X111541Y1381976I-141J-142D01*
G01X100112D01*
G37*
G36*
G01X157162Y986074D02*
X163087Y991998D01*
X164200D01*
G03X165159Y992317I0J1601D01*
G02X165798Y991997I239J-320D01*
G01Y978412D01*
X161090Y973704D01*
X157673D01*
G02X157277Y974162I0J400D01*
G03X157000Y975640I-2277J338D01*
G01Y977498D01*
X157162D01*
Y986074D01*
G37*
%LPC*%
G75*
G54D111*
X105000Y55000D03*
G54D107*
X15906Y78110D03*
Y1217323D03*
Y1477165D03*
Y1910394D03*
G54D110*
X96457Y1747835D03*
Y1823031D03*
%LPD*%
G75*
G54D100*
G01X-430254Y-152763D02*
Y-135263D01*
G01X-421958D02*
X-430254Y-146055D01*
G01X-420648Y-152763D02*
X-426543Y-141097D01*
G01X-412973Y-152763D02*
Y-135263D01*
X-402929Y-152763D01*
Y-135263D01*
G01X-390451Y-152763D02*
X-392198Y-152471D01*
X-393726Y-151305D01*
X-395036Y-149555D01*
X-395910Y-147513D01*
X-396346Y-145180D01*
Y-142846D01*
X-395910Y-140513D01*
X-395036Y-138471D01*
X-393726Y-136722D01*
X-392198Y-135555D01*
X-390451Y-135263D01*
X-388705Y-135555D01*
X-387176Y-136722D01*
X-385866Y-138471D01*
X-384992Y-140513D01*
X-384556Y-142846D01*
Y-145180D01*
X-384992Y-147513D01*
X-385866Y-149555D01*
X-387176Y-151305D01*
X-388705Y-152471D01*
X-390451Y-152763D01*
G01X-377536D02*
X-368366Y-135263D01*
G01X-377536D02*
X-368366Y-152763D01*
G01X-362001Y-158596D02*
X-348901D01*
G01X-342099Y-152763D02*
Y-135263D01*
X-333803D01*
G01X-336859Y-143721D02*
X-342099D01*
G01X-325910Y-152763D02*
X-320451Y-135263D01*
X-314992Y-152763D01*
G01X-316958Y-146638D02*
X-323945D01*
G01X-307973Y-152763D02*
Y-135263D01*
X-297929Y-152763D01*
Y-135263D01*
G01X-263148Y-136722D02*
X-264458Y-135846D01*
X-265986Y-135263D01*
X-267733D01*
X-269698Y-136138D01*
X-271226Y-137596D01*
X-272318Y-139347D01*
X-273191Y-142263D01*
X-273410Y-144888D01*
X-272973Y-147513D01*
X-272318Y-149263D01*
X-271008Y-151013D01*
X-269479Y-152180D01*
X-267951Y-152763D01*
X-266423D01*
X-264894Y-152180D01*
X-263584Y-151305D01*
X-262492Y-150139D01*
G01X-250451Y-152763D02*
X-252198Y-152471D01*
X-253726Y-151305D01*
X-255036Y-149555D01*
X-255910Y-147513D01*
X-256346Y-145180D01*
Y-142846D01*
X-255910Y-140513D01*
X-255036Y-138471D01*
X-253726Y-136722D01*
X-252198Y-135555D01*
X-250451Y-135263D01*
X-248705Y-135555D01*
X-247176Y-136722D01*
X-245866Y-138471D01*
X-244992Y-140513D01*
X-244556Y-142846D01*
Y-145180D01*
X-244992Y-147513D01*
X-245866Y-149555D01*
X-247176Y-151305D01*
X-248705Y-152471D01*
X-250451Y-152763D01*
G01X-237973D02*
Y-135263D01*
X-227929Y-152763D01*
Y-135263D01*
G01X-215451D02*
Y-152763D01*
G01X-220473Y-135263D02*
X-210429D01*
G01X-202318Y-152763D02*
Y-135263D01*
X-196859D01*
X-195113Y-136138D01*
X-194021Y-137305D01*
X-193584Y-139638D01*
X-194021Y-141972D01*
X-195331Y-143430D01*
X-196859Y-144305D01*
X-202318D01*
G01X-196859D02*
X-193584Y-152763D01*
G01X-180451D02*
X-182198Y-152471D01*
X-183726Y-151305D01*
X-185036Y-149555D01*
X-185910Y-147513D01*
X-186346Y-145180D01*
Y-142846D01*
X-185910Y-140513D01*
X-185036Y-138471D01*
X-183726Y-136722D01*
X-182198Y-135555D01*
X-180451Y-135263D01*
X-178705Y-135555D01*
X-177176Y-136722D01*
X-175866Y-138471D01*
X-174992Y-140513D01*
X-174556Y-142846D01*
Y-145180D01*
X-174992Y-147513D01*
X-175866Y-149555D01*
X-177176Y-151305D01*
X-178705Y-152471D01*
X-180451Y-152763D01*
G01X-167318Y-135263D02*
Y-152763D01*
X-158584D01*
G01X-126205Y-143430D02*
X-125331Y-142555D01*
X-124676Y-141097D01*
X-124239Y-139054D01*
X-124676Y-137305D01*
X-125549Y-136138D01*
X-127078Y-135263D01*
X-132973D01*
Y-152763D01*
X-125768D01*
X-124239Y-151597D01*
X-123366Y-149846D01*
X-122929Y-147805D01*
X-123366Y-145763D01*
X-124676Y-144013D01*
X-126205Y-143430D01*
X-132973D01*
G01X-110451Y-152763D02*
X-112198Y-152471D01*
X-113726Y-151305D01*
X-115036Y-149555D01*
X-115910Y-147513D01*
X-116346Y-145180D01*
Y-142846D01*
X-115910Y-140513D01*
X-115036Y-138471D01*
X-113726Y-136722D01*
X-112198Y-135555D01*
X-110451Y-135263D01*
X-108705Y-135555D01*
X-107176Y-136722D01*
X-105866Y-138471D01*
X-104992Y-140513D01*
X-104556Y-142846D01*
Y-145180D01*
X-104992Y-147513D01*
X-105866Y-149555D01*
X-107176Y-151305D01*
X-108705Y-152471D01*
X-110451Y-152763D01*
G01X-98410D02*
X-92951Y-135263D01*
X-87492Y-152763D01*
G01X-89458Y-146638D02*
X-96445D01*
G01X-79818Y-152763D02*
Y-135263D01*
X-74359D01*
X-72613Y-136138D01*
X-71521Y-137305D01*
X-71084Y-139638D01*
X-71521Y-141972D01*
X-72831Y-143430D01*
X-74359Y-144305D01*
X-79818D01*
G01X-74359D02*
X-71084Y-152763D01*
G01X-62754D02*
Y-135263D01*
X-58388D01*
X-56641Y-136138D01*
X-55331Y-137305D01*
X-54239Y-139054D01*
X-53366Y-141097D01*
X-53148Y-144013D01*
X-53366Y-146930D01*
X-54239Y-148972D01*
X-55331Y-150722D01*
X-56641Y-151888D01*
X-58388Y-152763D01*
X-62754D01*
G01X-282378Y-107763D02*
Y-90263D01*
X-276701Y-104846D01*
X-271024Y-90263D01*
Y-107763D01*
G01X-259201D02*
X-260511Y-107471D01*
X-261821Y-106305D01*
X-262695Y-104263D01*
X-263131Y-101930D01*
X-262695Y-99596D01*
X-261821Y-97555D01*
X-260511Y-96388D01*
X-259201Y-96097D01*
X-257891Y-96388D01*
X-256581Y-97555D01*
X-255708Y-99596D01*
X-255489Y-101930D01*
X-255708Y-104263D01*
X-256581Y-106305D01*
X-257891Y-107471D01*
X-259201Y-107763D01*
G01X-237771Y-90263D02*
Y-107763D01*
G01Y-105139D02*
X-238644Y-106597D01*
X-239955Y-107471D01*
X-241483Y-107763D01*
X-243229Y-107180D01*
X-244539Y-105722D01*
X-245413Y-103972D01*
X-245631Y-101930D01*
X-245413Y-99888D01*
X-244539Y-98138D01*
X-243229Y-96680D01*
X-241483Y-96097D01*
X-239955Y-96388D01*
X-238863Y-96972D01*
X-237771Y-98138D01*
G01X-227476Y-99888D02*
X-220489D01*
X-221144Y-97846D01*
X-222236Y-96680D01*
X-223764Y-96097D01*
X-225293Y-96388D01*
X-226603Y-97263D01*
X-227476Y-99305D01*
X-227913Y-101055D01*
Y-102805D01*
X-227476Y-104555D01*
X-226384Y-106305D01*
X-225074Y-107471D01*
X-223546Y-107763D01*
X-222018Y-107180D01*
X-220489Y-105430D01*
G01X-206701Y-107763D02*
Y-90263D01*
G01X-14018Y-107763D02*
Y-90263D01*
X-8778D01*
X-7031Y-91138D01*
X-5721Y-93180D01*
X-5284Y-95513D01*
X-5721Y-97846D01*
X-6813Y-99596D01*
X-8778Y-100472D01*
X-14018D01*
G01X12652Y-91722D02*
X11342Y-90846D01*
X9814Y-90263D01*
X8067D01*
X6102Y-91138D01*
X4574Y-92596D01*
X3482Y-94347D01*
X2609Y-97263D01*
X2390Y-99888D01*
X2827Y-102513D01*
X3482Y-104263D01*
X4792Y-106013D01*
X6321Y-107180D01*
X7849Y-107763D01*
X9377D01*
X10906Y-107180D01*
X12216Y-106305D01*
X13308Y-105139D01*
G01X27095Y-98430D02*
X27969Y-97555D01*
X28624Y-96097D01*
X29061Y-94054D01*
X28624Y-92305D01*
X27751Y-91138D01*
X26222Y-90263D01*
X20327D01*
Y-107763D01*
X27532D01*
X29061Y-106597D01*
X29934Y-104846D01*
X30371Y-102805D01*
X29934Y-100763D01*
X28624Y-99013D01*
X27095Y-98430D01*
X20327D01*
G01X36299Y-113596D02*
X49399D01*
G01X55327Y-107763D02*
Y-90263D01*
X65371Y-107763D01*
Y-90263D01*
G01X77849Y-107763D02*
X76102Y-107471D01*
X74574Y-106305D01*
X73264Y-104555D01*
X72390Y-102513D01*
X71954Y-100180D01*
Y-97846D01*
X72390Y-95513D01*
X73264Y-93471D01*
X74574Y-91722D01*
X76102Y-90555D01*
X77849Y-90263D01*
X79595Y-90555D01*
X81124Y-91722D01*
X82434Y-93471D01*
X83308Y-95513D01*
X83744Y-97846D01*
Y-100180D01*
X83308Y-102513D01*
X82434Y-104555D01*
X81124Y-106305D01*
X79595Y-107471D01*
X77849Y-107763D01*
G01X-901Y-152763D02*
Y-135263D01*
X-3521Y-138763D01*
G01Y-152763D02*
X1719D01*
G01X12451Y-138180D02*
X13761Y-136430D01*
X15289Y-135555D01*
X17036Y-135263D01*
X19219Y-135846D01*
X20747Y-137305D01*
X21184Y-139054D01*
X20966Y-140805D01*
X20092Y-142263D01*
X15726Y-145180D01*
X13761Y-147221D01*
X12451Y-150139D01*
X12014Y-152763D01*
X21184D01*
G01X36719D02*
Y-135263D01*
X28640Y-147805D01*
X39558D01*
G01X46796Y-149263D02*
X48105Y-151305D01*
X49852Y-152471D01*
X51817Y-152763D01*
X53564Y-152471D01*
X55311Y-151013D01*
X56402Y-149263D01*
X56621Y-147513D01*
X56184Y-145472D01*
X54656Y-144013D01*
X53127Y-143430D01*
X51162D01*
G01X53127D02*
X54437Y-142555D01*
X55529Y-141097D01*
X55966Y-139347D01*
X55529Y-137596D01*
X54437Y-136138D01*
X52472Y-135263D01*
X50507Y-135555D01*
X48542Y-136722D01*
G01X64296Y-149263D02*
X65605Y-151305D01*
X67352Y-152471D01*
X69317Y-152763D01*
X71064Y-152471D01*
X72811Y-151013D01*
X73902Y-149263D01*
X74121Y-147513D01*
X73684Y-145472D01*
X72156Y-144013D01*
X70627Y-143430D01*
X68662D01*
G01X70627D02*
X71937Y-142555D01*
X73029Y-141097D01*
X73466Y-139347D01*
X73029Y-137596D01*
X71937Y-136138D01*
X69972Y-135263D01*
X68007Y-135555D01*
X66042Y-136722D01*
G01X128690Y-90263D02*
X134149Y-107763D01*
X139608Y-90263D01*
G01X156016Y-107763D02*
X147282D01*
Y-90263D01*
X156016D01*
G01X152522Y-98721D02*
X147282D01*
G01X164782Y-107763D02*
Y-90263D01*
X170241D01*
X171987Y-91138D01*
X173079Y-92305D01*
X173516Y-94638D01*
X173079Y-96972D01*
X171769Y-98430D01*
X170241Y-99305D01*
X164782D01*
G01X170241D02*
X173516Y-107763D01*
G01X186649Y-108346D02*
X186212Y-108055D01*
Y-107471D01*
X186649Y-107180D01*
X187086Y-107471D01*
Y-108055D01*
X186649Y-108346D01*
G01X147501Y-138180D02*
X148811Y-136430D01*
X150339Y-135555D01*
X152086Y-135263D01*
X154269Y-135846D01*
X155797Y-137305D01*
X156234Y-139054D01*
X156016Y-140805D01*
X155142Y-142263D01*
X150776Y-145180D01*
X148811Y-147221D01*
X147501Y-150139D01*
X147064Y-152763D01*
X156234D01*
G01X163690D02*
X169149Y-135263D01*
X174608Y-152763D01*
G01X172642Y-146638D02*
X165655D01*
G01X253482Y-90263D02*
Y-107763D01*
X262216D01*
G01X279279D02*
Y-96097D01*
G01Y-98138D02*
X278406Y-96972D01*
X277095Y-96388D01*
X275567Y-96097D01*
X274039Y-96680D01*
X272729Y-97846D01*
X271855Y-99596D01*
X271419Y-101930D01*
X271855Y-104263D01*
X272729Y-106013D01*
X274039Y-107180D01*
X275567Y-107763D01*
X277095Y-107471D01*
X278406Y-106597D01*
X279279Y-105430D01*
G01X288264Y-113013D02*
X289574Y-113596D01*
X291321Y-113013D01*
X292412Y-111847D01*
X293286Y-110388D01*
X294595Y-105722D01*
X297434Y-96097D01*
G01X290447D02*
X294595Y-105722D01*
G01X307074Y-99888D02*
X314061D01*
X313406Y-97846D01*
X312314Y-96680D01*
X310786Y-96097D01*
X309257Y-96388D01*
X307947Y-97263D01*
X307074Y-99305D01*
X306637Y-101055D01*
Y-102805D01*
X307074Y-104555D01*
X308166Y-106305D01*
X309476Y-107471D01*
X311004Y-107763D01*
X312532Y-107180D01*
X314061Y-105430D01*
G01X324792Y-107763D02*
Y-96097D01*
G01Y-98430D02*
X325884Y-97263D01*
X326976Y-96388D01*
X328504Y-96097D01*
X329595Y-96388D01*
X330906Y-97263D01*
G01X342074Y-105722D02*
X343166Y-106888D01*
X344694Y-107763D01*
X346004D01*
X347314Y-107180D01*
X348187Y-106305D01*
X348624Y-105139D01*
X348406Y-103388D01*
X347532Y-102513D01*
X343602Y-100763D01*
X342729Y-98721D01*
X343166Y-97263D01*
X344039Y-96388D01*
X345349Y-96097D01*
X346659Y-96388D01*
X347969Y-97263D01*
G01X288482Y-135263D02*
Y-152763D01*
X297216D01*
G01X310349D02*
Y-135263D01*
X307729Y-138763D01*
G01Y-152763D02*
X312969D01*
G01X404346Y-107763D02*
Y-90263D01*
X408712D01*
X410459Y-91138D01*
X411769Y-92305D01*
X412861Y-94054D01*
X413734Y-96097D01*
X413952Y-99013D01*
X413734Y-101930D01*
X412861Y-103972D01*
X411769Y-105722D01*
X410459Y-106888D01*
X408712Y-107763D01*
X404346D01*
G01X423374Y-99888D02*
X430361D01*
X429706Y-97846D01*
X428614Y-96680D01*
X427086Y-96097D01*
X425557Y-96388D01*
X424247Y-97263D01*
X423374Y-99305D01*
X422937Y-101055D01*
Y-102805D01*
X423374Y-104555D01*
X424466Y-106305D01*
X425776Y-107471D01*
X427304Y-107763D01*
X428832Y-107180D01*
X430361Y-105430D01*
G01X440874Y-105722D02*
X441966Y-106888D01*
X443494Y-107763D01*
X444804D01*
X446114Y-107180D01*
X446987Y-106305D01*
X447424Y-105139D01*
X447206Y-103388D01*
X446332Y-102513D01*
X442402Y-100763D01*
X441529Y-98721D01*
X441966Y-97263D01*
X442839Y-96388D01*
X444149Y-96097D01*
X445459Y-96388D01*
X446769Y-97263D01*
G01X461649Y-96097D02*
Y-107763D01*
G01Y-91430D02*
X461212Y-91138D01*
Y-90555D01*
X461649Y-90263D01*
X462086Y-90555D01*
Y-91138D01*
X461649Y-91430D01*
G01X476092Y-112138D02*
X477621Y-113305D01*
X479367Y-113596D01*
X480895Y-113305D01*
X482206Y-111847D01*
X483079Y-109805D01*
Y-96097D01*
G01Y-98430D02*
X482206Y-97263D01*
X480895Y-96388D01*
X479367Y-96097D01*
X477621Y-96680D01*
X476529Y-97846D01*
X475655Y-99888D01*
X475219Y-101930D01*
X475437Y-103680D01*
X476311Y-105722D01*
X477621Y-107180D01*
X479367Y-107763D01*
X480677Y-107471D01*
X482206Y-106305D01*
X483079Y-105139D01*
G01X492937Y-107763D02*
Y-96097D01*
G01Y-99013D02*
X493811Y-97555D01*
X495121Y-96388D01*
X496867Y-96097D01*
X498395Y-96388D01*
X499706Y-97555D01*
X500361Y-99596D01*
Y-107763D01*
G01X510874Y-99888D02*
X517861D01*
X517206Y-97846D01*
X516114Y-96680D01*
X514586Y-96097D01*
X513057Y-96388D01*
X511747Y-97263D01*
X510874Y-99305D01*
X510437Y-101055D01*
Y-102805D01*
X510874Y-104555D01*
X511966Y-106305D01*
X513276Y-107471D01*
X514804Y-107763D01*
X516332Y-107180D01*
X517861Y-105430D01*
G01X528592Y-107763D02*
Y-96097D01*
G01Y-98430D02*
X529684Y-97263D01*
X530776Y-96388D01*
X532304Y-96097D01*
X533395Y-96388D01*
X534706Y-97263D01*
G01X429722Y-152763D02*
Y-135263D01*
X435399Y-149846D01*
X441076Y-135263D01*
Y-152763D01*
G01X452899D02*
X451152Y-152471D01*
X449624Y-151305D01*
X448314Y-149555D01*
X447440Y-147513D01*
X447004Y-145180D01*
Y-142846D01*
X447440Y-140513D01*
X448314Y-138471D01*
X449624Y-136722D01*
X451152Y-135555D01*
X452899Y-135263D01*
X454645Y-135555D01*
X456174Y-136722D01*
X457484Y-138471D01*
X458358Y-140513D01*
X458794Y-142846D01*
Y-145180D01*
X458358Y-147513D01*
X457484Y-149555D01*
X456174Y-151305D01*
X454645Y-152471D01*
X452899Y-152763D01*
G01X465814Y-150430D02*
X467561Y-151888D01*
X469526Y-152763D01*
X471272D01*
X473019Y-151888D01*
X474329Y-150430D01*
X474984Y-148388D01*
X474547Y-146347D01*
X473456Y-144596D01*
X471491Y-143430D01*
X468871Y-142846D01*
X467342Y-141680D01*
X466687Y-139638D01*
X467124Y-137596D01*
X468216Y-136138D01*
X469744Y-135263D01*
X471272D01*
X472801Y-135846D01*
X474111Y-137305D01*
G01X483314Y-150430D02*
X485061Y-151888D01*
X487026Y-152763D01*
X488772D01*
X490519Y-151888D01*
X491829Y-150430D01*
X492484Y-148388D01*
X492047Y-146347D01*
X490956Y-144596D01*
X488991Y-143430D01*
X486371Y-142846D01*
X484842Y-141680D01*
X484187Y-139638D01*
X484624Y-137596D01*
X485716Y-136138D01*
X487244Y-135263D01*
X488772D01*
X490301Y-135846D01*
X491611Y-137305D01*
G01X509766Y-152763D02*
X501032D01*
Y-135263D01*
X509766D01*
G01X506272Y-143721D02*
X501032D01*
G01X575349Y-152763D02*
Y-135263D01*
X572729Y-138763D01*
G01Y-152763D02*
X577969D01*
G01X588701Y-138180D02*
X590011Y-136430D01*
X591539Y-135555D01*
X593286Y-135263D01*
X595469Y-135846D01*
X596997Y-137305D01*
X597434Y-139054D01*
X597216Y-140805D01*
X596342Y-142263D01*
X591976Y-145180D01*
X590011Y-147221D01*
X588701Y-150139D01*
X588264Y-152763D01*
X597434D01*
G01X606419Y-153346D02*
X614279Y-135263D01*
G01X627849Y-152763D02*
Y-135263D01*
X625229Y-138763D01*
G01Y-152763D02*
X630469D01*
G01X645349D02*
Y-135263D01*
X642729Y-138763D01*
G01Y-152763D02*
X647969D01*
G01X658919Y-153346D02*
X666779Y-135263D01*
G01X676201Y-138180D02*
X677511Y-136430D01*
X679039Y-135555D01*
X680786Y-135263D01*
X682969Y-135846D01*
X684497Y-137305D01*
X684934Y-139054D01*
X684716Y-140805D01*
X683842Y-142263D01*
X679476Y-145180D01*
X677511Y-147221D01*
X676201Y-150139D01*
X675764Y-152763D01*
X684934D01*
G01X697849Y-135263D02*
X696102Y-135846D01*
X694792Y-137305D01*
X693919Y-139054D01*
X693264Y-141388D01*
X693046Y-144013D01*
X693264Y-146638D01*
X693919Y-148972D01*
X694792Y-150722D01*
X696102Y-152180D01*
X697849Y-152763D01*
X699595Y-152180D01*
X700906Y-150722D01*
X701779Y-148972D01*
X702434Y-146638D01*
X702652Y-144013D01*
X702434Y-141388D01*
X701779Y-139054D01*
X700906Y-137305D01*
X699595Y-135846D01*
X697849Y-135263D01*
G01X715349Y-152763D02*
Y-135263D01*
X712729Y-138763D01*
G01Y-152763D02*
X717969D01*
G01X728046Y-150139D02*
X729355Y-151597D01*
X730884Y-152471D01*
X732849Y-152763D01*
X734814Y-152180D01*
X736342Y-151013D01*
X737434Y-148972D01*
X737652Y-146638D01*
X737216Y-144305D01*
X736124Y-142846D01*
X734595Y-141680D01*
X733067Y-141388D01*
X731539Y-141680D01*
X729574Y-142846D01*
X730229Y-135263D01*
X736124D01*
G01X623046Y-107763D02*
Y-90263D01*
X627412D01*
X629159Y-91138D01*
X630469Y-92305D01*
X631561Y-94054D01*
X632434Y-96097D01*
X632652Y-99013D01*
X632434Y-101930D01*
X631561Y-103972D01*
X630469Y-105722D01*
X629159Y-106888D01*
X627412Y-107763D01*
X623046D01*
G01X649279D02*
Y-96097D01*
G01Y-98138D02*
X648406Y-96972D01*
X647095Y-96388D01*
X645567Y-96097D01*
X644039Y-96680D01*
X642729Y-97846D01*
X641855Y-99596D01*
X641419Y-101930D01*
X641855Y-104263D01*
X642729Y-106013D01*
X644039Y-107180D01*
X645567Y-107763D01*
X647095Y-107471D01*
X648406Y-106597D01*
X649279Y-105430D01*
G01X662849Y-90263D02*
Y-107763D01*
G01X659792Y-96097D02*
X665906D01*
G01X677074Y-99888D02*
X684061D01*
X683406Y-97846D01*
X682314Y-96680D01*
X680786Y-96097D01*
X679257Y-96388D01*
X677947Y-97263D01*
X677074Y-99305D01*
X676637Y-101055D01*
Y-102805D01*
X677074Y-104555D01*
X678166Y-106305D01*
X679476Y-107471D01*
X681004Y-107763D01*
X682532Y-107180D01*
X684061Y-105430D01*
G54D101*
G01X67398Y71053D02*
X61951Y76500D01*
X41800D01*
X33410Y68110D01*
X15906D01*
G01X67998Y56553D02*
X64552D01*
X56109Y48110D01*
X15906D01*
G01X32425Y177900D02*
X32925Y177400D01*
X58250D01*
X60350Y175300D01*
G01X36132Y264217D02*
X36324Y264025D01*
X41424D01*
X44700Y260749D01*
Y244267D01*
X31299Y230866D01*
G01Y220866D02*
X28834D01*
X25500Y224200D01*
Y233700D01*
X33500Y241700D01*
Y249750D01*
X37200Y253450D01*
G01X31299Y210866D02*
Y213201D01*
X23750Y220750D01*
Y234750D01*
X27900Y238900D01*
Y246900D01*
G01X32700Y253450D02*
X25199D01*
X23596Y255053D01*
G01X32700Y253450D02*
Y251700D01*
X27900Y246900D01*
G01X27471Y262553D02*
Y269042D01*
X27900Y269471D01*
G01X32632Y264217D02*
Y264739D01*
X27900Y269471D01*
G01X31299Y358563D02*
X32913D01*
X43500Y347976D01*
Y322703D01*
X30297Y309500D01*
X20515D01*
X19283Y310732D01*
G01X36300Y328500D02*
Y325050D01*
X32550Y321300D01*
G01X36300Y328500D02*
Y333562D01*
X31299Y338563D01*
G01X36200Y318700D02*
X35950Y318450D01*
X32800D01*
X28800Y314450D01*
Y312850D01*
G01X32550Y321300D02*
X33600D01*
X36200Y318700D01*
G01X19283Y307232D02*
Y303709D01*
X20010Y302982D01*
G01D02*
X20028Y303000D01*
X22575D01*
X24925Y305350D01*
G01X31299Y348563D02*
X37887D01*
X39200Y347250D01*
G01X64450Y573000D02*
X63500Y572050D01*
Y572000D01*
X54101Y562601D01*
X26156D01*
X23275Y565482D01*
Y569573D01*
X23273Y569575D01*
Y572025D01*
X23275Y572027D01*
Y575344D01*
X23400Y575469D01*
Y577441D01*
X23450Y577491D01*
G01X25148Y570800D02*
X25046Y570902D01*
Y572960D01*
X25025Y572981D01*
Y574619D01*
X27100Y576694D01*
Y578100D01*
G01D02*
X29600D01*
X32850Y581350D01*
X35000D01*
G01X46500Y705500D02*
X42525D01*
X33075Y696050D01*
Y688925D01*
X34000Y688000D01*
X36250D01*
G01X15906Y761181D02*
X23319D01*
X30544Y753956D01*
X58544D01*
X67500Y745000D01*
X71650D01*
X75200Y741450D01*
G01X75700Y719050D02*
Y721000D01*
X74700Y722000D01*
X65000D01*
X51000Y736000D01*
X21087D01*
X15906Y741181D01*
G01X43400Y896150D02*
X39066D01*
X31299Y903917D01*
G01Y923917D02*
X35716Y919500D01*
X58600D01*
X64100Y914000D01*
Y912850D01*
G01X31299Y913917D02*
X33782Y916400D01*
X45350D01*
G01X31299Y1054587D02*
X28113D01*
X24400Y1058300D01*
Y1074749D01*
X30050Y1080399D01*
Y1083600D01*
G01X31299Y1044587D02*
Y1048926D01*
X22650Y1057575D01*
Y1091365D01*
X24368Y1093083D01*
G01X39000Y1033500D02*
Y1036886D01*
X31299Y1044587D01*
G01X41450Y1096000D02*
Y1084300D01*
X31299Y1074149D01*
Y1064587D01*
G01X24250Y1106000D02*
Y1102250D01*
X24500Y1102000D01*
G01D02*
X24368Y1101868D01*
Y1093083D01*
G01X31868Y1089208D02*
X34708D01*
X37200Y1091700D01*
G01X15906Y1207323D02*
X26401Y1196828D01*
Y1192601D01*
X48500Y1170502D01*
Y1036500D01*
X55000Y1030000D01*
X57250D01*
X58100Y1030850D01*
G01X15906Y1187323D02*
X25177D01*
X44500Y1168000D01*
Y1016500D01*
X47950Y1013050D01*
X53800D01*
G01X31299Y1619941D02*
X25300Y1625940D01*
Y1636950D01*
X22050Y1640200D01*
G01X31299Y1609941D02*
X34574Y1613216D01*
Y1621298D01*
X28024Y1627848D01*
Y1635024D01*
X31500Y1638500D01*
Y1641550D01*
G01X31299Y1629941D02*
Y1633799D01*
X38000Y1640500D01*
Y1659150D01*
X32900Y1664250D01*
G01D02*
X20400D01*
X19250Y1663100D01*
G01X31500Y1641550D02*
X26450D01*
X23700Y1644300D01*
X22050D01*
G01X27200Y1657100D02*
X22050Y1651950D01*
Y1644300D01*
G01X35375Y1649050D02*
Y1653825D01*
X32900Y1656300D01*
G01D02*
Y1660750D01*
G01X18350Y1720700D02*
Y1744689D01*
X31299Y1757638D01*
G01X18350Y1720700D02*
Y1718523D01*
X16700Y1716873D01*
Y1709500D01*
X19200Y1707000D01*
G01X31299Y1747638D02*
X25900Y1742239D01*
Y1725150D01*
G01X27292Y1714868D02*
X25732D01*
X21850Y1718750D01*
Y1720700D01*
G01X33000Y1718500D02*
X29368Y1714868D01*
X27292D01*
G01X26800Y1699200D02*
Y1695950D01*
X23650Y1692800D01*
G01X23417Y1707368D02*
X23799Y1707750D01*
X31248D01*
X32949Y1709451D01*
G01X23417Y1707368D02*
Y1702583D01*
X26800Y1699200D01*
G01X32949Y1709451D02*
X35500Y1712002D01*
Y1733437D01*
X31299Y1737638D01*
G01X27800Y1769900D02*
X23650D01*
X23350Y1769600D01*
G01X27800Y1769900D02*
Y1766600D01*
X25000Y1763800D01*
G01X33800Y1769900D02*
Y1771200D01*
X31600Y1773400D01*
Y1773450D01*
X30650Y1774400D01*
G01X20056Y1774189D02*
X20011D01*
X19000Y1775200D01*
Y1778650D01*
X21350Y1781000D01*
G01X30650Y1774400D02*
X20267D01*
X20056Y1774189D01*
G01X30250Y1787800D02*
X31306D01*
X37787Y1794281D01*
X37881D01*
X54050Y1810450D01*
Y1863656D01*
X29706Y1888000D01*
X23512D01*
X15906Y1880394D01*
G01X30250Y1787800D02*
Y1783350D01*
X27900Y1781000D01*
X21350D01*
G01X15906Y1900394D02*
X23300Y1893000D01*
X31000D01*
X58000Y1866000D01*
Y1806500D01*
X57000Y1805500D01*
G01X84047Y61398D02*
X88149D01*
X88253Y61502D01*
G01X85750Y71500D02*
X81500D01*
G01Y75500D02*
Y71500D01*
G01X95850Y68500D02*
X78500D01*
X75500Y71500D01*
G01X71400Y71704D02*
X75296D01*
X75500Y71500D01*
G01X71400Y71704D02*
X68049D01*
X67398Y71053D01*
G01X67998Y56553D02*
X71746D01*
X71802Y56497D01*
G01D02*
X75958D01*
X77953Y54502D01*
G01X78047Y61398D02*
Y54596D01*
X77953Y54502D01*
G01X49924Y153261D02*
X50539D01*
X58275Y145525D01*
X64601D01*
X74376Y155300D01*
X75300D01*
G01X56600Y191550D02*
X53650D01*
X53400Y191300D01*
G01X56850Y187300D02*
Y191300D01*
X56600Y191550D01*
G01X39300Y175500D02*
Y174400D01*
X49700Y164000D01*
Y161500D01*
X55900Y155300D01*
X56850D01*
G01D02*
Y155800D01*
X60350Y159300D01*
G01D02*
X64400D01*
X71400Y166300D01*
X110800D01*
X143500Y199000D01*
X164197D01*
X169606Y204409D01*
G01X56850Y183300D02*
Y179300D01*
G01Y183300D02*
X45800D01*
X43700Y181200D01*
G01X56850Y163300D02*
Y167300D01*
G01D02*
X50425D01*
X43400Y174325D01*
G01X60350Y175300D02*
X63500D01*
X66000Y177800D01*
X113800D01*
X146000Y210000D01*
X150400D01*
X154400Y214000D01*
Y214500D01*
X157934Y218034D01*
X165981D01*
X169606Y214409D01*
G01X60350Y175300D02*
Y171300D01*
G01X52700Y162300D02*
Y161000D01*
X54400Y159300D01*
X56850D01*
G01X60350Y167300D02*
X69100Y176050D01*
X114975D01*
X114976Y176049D01*
X116424D01*
X116425Y176050D01*
X117050D01*
X141784Y200784D01*
X151284D01*
X153300Y202800D01*
Y208104D01*
X159605Y214409D01*
X159606D01*
G01X64400Y183400D02*
X60450D01*
X60350Y183300D01*
G01X56850Y175300D02*
X52600D01*
X52500Y175200D01*
G01X60350Y187300D02*
Y191300D01*
X60600Y191550D01*
G01X60350Y187300D02*
X61314Y188264D01*
X115764D01*
X146534Y219034D01*
X153150D01*
X153900Y219784D01*
X174231D01*
X179606Y214409D01*
G01X60600Y195050D02*
X65650D01*
X70500Y190200D01*
G01X41100Y231000D02*
X42775Y229325D01*
X58573D01*
X60523Y231275D01*
X66877D01*
X80118Y218034D01*
X97084D01*
X100709Y214409D01*
G01X57400Y211350D02*
X61600D01*
G01D02*
X68200D01*
X71400Y208150D01*
G01X69900Y236600D02*
X67500Y239000D01*
X63900D01*
X62850Y240050D01*
X61000D01*
G01X77900Y229034D02*
X105334D01*
X110709Y234409D01*
G01X56900Y240050D02*
X61000D01*
G01X80709Y224409D02*
X78659D01*
X72750Y230318D01*
Y234850D01*
X73375Y235475D01*
Y251650D01*
X71750Y253275D01*
X66625D01*
X62600Y249250D01*
G01X80709Y224409D02*
X84334Y220784D01*
X102211D01*
X104400Y222973D01*
Y223227D01*
X109207Y228034D01*
X145981D01*
X149606Y224409D01*
G01X61250Y221000D02*
Y217000D01*
G01Y221000D02*
X67200D01*
X70600Y217600D01*
G01X46450Y213400D02*
Y209364D01*
X52889Y202925D01*
X64975D01*
X68866Y199034D01*
X105334D01*
X110709Y204409D01*
G01X149606Y244409D02*
X137591D01*
X133950Y248050D01*
X84350D01*
X80709Y244409D01*
G01D02*
Y247291D01*
X63750Y264250D01*
X63000D01*
G01X46450Y217400D02*
Y220550D01*
X51200Y225300D01*
X68600D01*
X69400Y226100D01*
G01X74800Y231800D02*
Y233627D01*
X80473Y239300D01*
X102700D01*
X107809Y244409D01*
X110709D01*
G01X61300Y229400D02*
X58950Y227050D01*
X39450D01*
X38000Y228500D01*
G01X75300Y211300D02*
X72700Y213900D01*
X50450D01*
X49950Y213400D01*
G01X72100Y221700D02*
X70325Y223475D01*
X53474D01*
X49950Y219951D01*
Y217400D01*
G01X49700Y209700D02*
Y208849D01*
X53174Y205375D01*
X74775D01*
X78900Y209500D01*
X85800D01*
X90709Y214409D01*
G01X53500Y199700D02*
X48300D01*
X47800Y199200D01*
G01X56850Y199300D02*
Y195300D01*
X56600Y195050D01*
G01X64000Y199700D02*
X62525Y201175D01*
X58875D01*
X58500Y200800D01*
X58350D01*
X56850Y199300D01*
G01X60600Y195050D02*
Y199050D01*
X60350Y199300D01*
G01X60300Y275700D02*
X60000Y275400D01*
Y265050D01*
X58300Y263350D01*
G01X54300D02*
Y265300D01*
X57500Y268500D01*
G01X54000Y275600D02*
Y274700D01*
X48000Y268700D01*
X40615D01*
X36132Y264217D01*
G01X54300Y259850D02*
Y254900D01*
X56400Y252800D01*
G01X62600Y249250D02*
X59950D01*
X56400Y252800D01*
G01X58300Y259850D02*
X62550D01*
X62700Y260000D01*
G01X63000Y264250D02*
Y260300D01*
X62700Y260000D01*
G01X56850Y280000D02*
X48000D01*
X45800Y277800D01*
G01X43400Y272300D02*
X36250D01*
G01X73900Y555350D02*
Y550100D01*
G01D02*
X73700Y549900D01*
Y543350D01*
G01D02*
X76850D01*
X78250Y544750D01*
X81465D01*
G01X72500Y595900D02*
X72900Y596300D01*
X77000D01*
X78400Y594900D01*
Y591050D01*
G01X73700Y591000D02*
X78350D01*
X78400Y591050D01*
G01X56800Y576950D02*
X49600D01*
G01D02*
X45250D01*
X45100Y577100D01*
G01X67700Y591000D02*
X71650Y587050D01*
Y584000D01*
G01D02*
X64850Y577200D01*
X64450D01*
G01D02*
Y573000D01*
G01X45100Y583100D02*
Y592950D01*
X45050Y593000D01*
G01D02*
X40500D01*
X39400Y591900D01*
Y581750D01*
X39000Y581350D01*
G01D02*
X35000D01*
G01X102835Y632284D02*
X97816D01*
X93800Y636300D01*
Y646100D01*
X81100Y658800D01*
Y668200D01*
X80900Y668400D01*
G01X102835Y634249D02*
X98326D01*
X95550Y637025D01*
Y646826D01*
X94526Y647850D01*
X94525D01*
X91750Y650625D01*
Y650626D01*
X84268Y658108D01*
Y665568D01*
X84504Y665804D01*
Y666353D01*
G01X75571Y692496D02*
Y692529D01*
X75000Y693100D01*
Y700250D01*
X77200Y702450D01*
G01D02*
X81950D01*
X82000Y702400D01*
G01X81994Y694635D02*
X85495D01*
X86060Y695200D01*
G01X82006Y690465D02*
X81994Y690477D01*
Y694635D01*
G01X84150Y686400D02*
Y682900D01*
X83450Y682200D01*
G01X84150Y686400D02*
Y688050D01*
X86000Y689900D01*
G01X51750Y688000D02*
X49674D01*
X43388Y694286D01*
G01X49500Y703500D02*
X43000D01*
X36250Y696750D01*
Y690560D01*
G01X44500Y697500D02*
Y697000D01*
X50940Y690560D01*
X51750D01*
G01X69435Y674606D02*
Y676565D01*
X68219Y677781D01*
X65753D01*
X63875Y675903D01*
Y675824D01*
X62426Y674375D01*
X62425D01*
X61400Y673350D01*
G01X60500Y682540D02*
X60460D01*
X58250Y684750D01*
Y685440D01*
G01X60900Y670200D02*
X61400Y670700D01*
Y673350D01*
G01X42750Y685440D02*
X47590Y680600D01*
X49401D01*
X54925Y675076D01*
Y675075D01*
X56650Y673350D01*
X57400D01*
G01X57200Y667884D02*
X61884D01*
X63975Y669975D01*
X65350D01*
X66875Y671500D01*
Y674606D01*
G01X57400Y673350D02*
X57200Y673150D01*
Y667884D01*
G01X76100Y686900D02*
X71995Y682795D01*
Y681106D01*
G01X79950Y682200D02*
Y679950D01*
X81791Y678109D01*
X83850D01*
G01X77000Y727350D02*
X81450D01*
X81500Y727400D01*
G01X77000Y727350D02*
X73650D01*
X73000Y728000D01*
G01X81500Y733400D02*
X86250D01*
G01X81350Y740400D02*
X76250D01*
X75200Y741450D01*
G01X81350Y740400D02*
Y733550D01*
X81500Y733400D01*
G01X82000Y708400D02*
X87250D01*
X87750Y707900D01*
G01X81850Y715400D02*
Y708550D01*
X82000Y708400D01*
G01X75700Y719050D02*
X78200D01*
X81850Y715400D01*
G01X98900Y822900D02*
X72400D01*
G01X157800Y898000D02*
X157300Y897500D01*
X72500D01*
X62300Y887300D01*
X57800D01*
X56000Y885500D01*
G01X147500Y900500D02*
X146500Y899500D01*
X77500D01*
X76500Y900500D01*
G01X64100Y912850D02*
X64150D01*
X76500Y900500D01*
G01X43400Y896150D02*
X48550D01*
X49900Y894800D01*
G01X54817Y902368D02*
Y899717D01*
X49900Y894800D01*
G01X65900Y900000D02*
X57500D01*
X55132Y902368D01*
X54817D01*
G01X64100Y909350D02*
Y904800D01*
G01X58692Y909868D02*
X59210Y909350D01*
X64100D01*
G01X68650Y999800D02*
X65700D01*
X64200Y998300D01*
G01X54000Y996500D02*
X62400D01*
X64200Y998300D01*
G01X127200Y1015200D02*
X117200D01*
X96000Y994000D01*
X40100D01*
X37700Y991600D01*
G01X60150Y1011800D02*
X55050D01*
X53800Y1013050D01*
G01X64200Y1004300D02*
Y1007750D01*
X60150Y1011800D01*
G01X68650Y1004300D02*
X64200D01*
G01X61800Y1025000D02*
Y1021850D01*
X63050Y1020600D01*
G01X61800Y1025000D02*
X54000D01*
X53500Y1025500D01*
G01X67800Y1025000D02*
X71850D01*
X72250Y1025400D01*
G01X64450Y1032100D02*
Y1028350D01*
X67800Y1025000D01*
G01X64450Y1032100D02*
X59350D01*
X58100Y1030850D01*
G01X37500Y1099823D02*
X38677D01*
X41450Y1097050D01*
Y1096000D01*
G01X37950D02*
Y1092450D01*
X37200Y1091700D01*
G01X67302Y1133490D02*
Y1136798D01*
X65547Y1138553D01*
X63198D01*
G01D02*
X63202Y1138549D01*
Y1134147D01*
G01X81398Y1137953D02*
X77008D01*
X77002Y1137947D01*
G01X78292Y1148041D02*
X77961D01*
X75819Y1145899D01*
Y1139130D01*
X77002Y1137947D01*
G01X71150Y1144500D02*
X70202Y1143552D01*
Y1138347D01*
G01X63202Y1128147D02*
X66370Y1131315D01*
X68204D01*
X70202Y1133313D01*
Y1138347D01*
G01X63498Y1123853D02*
X63202Y1124149D01*
Y1128147D01*
G01X70500Y1161500D02*
Y1145150D01*
X71150Y1144500D01*
G01X81398Y1126153D02*
X81498Y1126253D01*
Y1131853D01*
X81398Y1131953D01*
G01X88502Y1136247D02*
X84208Y1131953D01*
X81398D01*
G01X86950Y1143000D02*
Y1144993D01*
X73163Y1158780D01*
G01X45300Y1776300D02*
X48850Y1772750D01*
Y1770300D01*
X49350Y1769800D01*
G01X54500Y1764700D02*
X54450D01*
X49350Y1769800D01*
G01X48250Y1760300D02*
Y1764450D01*
X48500Y1764700D01*
G01X41600Y1767550D02*
Y1762100D01*
X45700Y1758000D01*
X46050D01*
X48250Y1755800D01*
G01D02*
X48300Y1755750D01*
G01X48250Y1760300D02*
Y1755800D01*
G01X48500Y1764700D02*
Y1765000D01*
X45300Y1768200D01*
Y1772600D01*
X43200Y1774700D01*
Y1780700D01*
X45150Y1782650D01*
Y1793650D01*
X57000Y1805500D01*
G01X88253Y61502D02*
Y65500D01*
G01X179606Y224409D02*
X175981Y228034D01*
X158103D01*
X154700Y224631D01*
Y224200D01*
X151284Y220784D01*
X114334D01*
X110709Y224409D01*
G01X117600Y234900D02*
X121100D01*
X124234Y238034D01*
X175981D01*
X179606Y234409D01*
G01Y244409D02*
X183200Y240815D01*
Y235942D01*
X183231Y235911D01*
Y232907D01*
X183200Y232876D01*
Y232300D01*
X181684Y230784D01*
X122784D01*
X122100Y230100D01*
G01X179606Y204409D02*
X184980Y209783D01*
Y232181D01*
X184981Y232182D01*
Y236636D01*
X184980Y236637D01*
Y245320D01*
X182266Y248034D01*
X176934D01*
X174200Y245300D01*
Y243484D01*
X171500Y240784D01*
X124484D01*
X122700Y239000D01*
X110173D01*
X107000Y235827D01*
Y235573D01*
X102211Y230784D01*
X85992D01*
X85676Y231100D01*
G01X127200Y246000D02*
X121984Y240784D01*
X107084D01*
X100709Y234409D01*
G01X136771Y548521D02*
X136779Y548513D01*
Y543121D01*
G01D02*
X136950Y542950D01*
X145265D01*
G01X136679Y553721D02*
Y548613D01*
X136771Y548521D01*
G01X107600Y558300D02*
Y556800D01*
X112600Y551800D01*
X115300D01*
G01X90630Y602020D02*
X92465Y603855D01*
Y606921D01*
G01X128900Y588646D02*
X128892Y588654D01*
X124900D01*
G01X120520Y612629D02*
Y598980D01*
X120800Y598700D01*
G01D02*
Y593900D01*
X124900Y589800D01*
Y588654D01*
G01X129000Y597000D02*
Y599030D01*
X127810Y600220D01*
Y600254D01*
X124455Y603609D01*
Y612629D01*
G01X132735Y593429D02*
Y597770D01*
X129560Y600945D01*
Y600979D01*
X126425Y604114D01*
Y612629D01*
G01X128395D02*
Y605469D01*
X131935Y601929D01*
G01X140135Y593229D02*
Y598129D01*
X130360Y607904D01*
Y612629D01*
G01X108710D02*
Y609710D01*
X105000Y606000D01*
Y603200D01*
G01D02*
Y598950D01*
X103500Y597450D01*
G01X97265Y597521D02*
X98808Y599064D01*
Y604821D01*
X99578Y605591D01*
Y605771D01*
G01X102835Y618504D02*
Y605028D01*
X101105Y603298D01*
Y597861D01*
X97265Y594021D01*
G01X112018Y574741D02*
Y584900D01*
G01X112645Y612629D02*
Y608442D01*
X110200Y605997D01*
Y594650D01*
X111150Y593700D01*
G01D02*
X110500Y593050D01*
Y586418D01*
X112018Y584900D01*
G01X107650Y593700D02*
X108500Y592850D01*
Y587500D01*
X106400Y585400D01*
Y580558D01*
X106338Y580496D01*
G01X104518Y570866D02*
X106338Y572686D01*
Y580496D01*
G01X110675Y612629D02*
Y608947D01*
X108450Y606722D01*
Y594500D01*
X107650Y593700D01*
G01X112018Y566991D02*
X108393D01*
X104518Y570866D01*
G01X116580Y612629D02*
Y603630D01*
X116450Y603500D01*
G01D02*
Y597350D01*
X116000Y596900D01*
G01X112950Y603500D02*
Y600068D01*
X113655Y599363D01*
G01X114615Y612629D02*
Y605165D01*
X112950Y603500D01*
G01X118550Y612629D02*
Y608242D01*
X118565Y608227D01*
Y592846D01*
G01X116800Y588646D02*
X120792D01*
X120800Y588654D01*
G01X118565Y592846D02*
X118700D01*
X119692Y591854D01*
X119700D01*
X120800Y590754D01*
Y588654D01*
G01X125835Y593629D02*
Y598155D01*
X122490Y601500D01*
Y612629D01*
G01X94545Y601197D02*
X95850Y602502D01*
Y619625D01*
X98664Y622439D01*
X102835D01*
G01X93065Y597521D02*
Y599630D01*
X94545Y601110D01*
Y601197D01*
G01X96500Y567600D02*
Y563700D01*
X96300Y563500D01*
G01X91300Y569750D02*
X94350D01*
X96500Y567600D01*
G01X89335Y561050D02*
Y567785D01*
X91300Y569750D01*
G01X96300Y563500D02*
X98800D01*
X101500Y560800D01*
X105100D01*
X107600Y558300D01*
G01X138900Y650100D02*
X138599Y650401D01*
X132001D01*
X130360Y648760D01*
Y646029D01*
G01X139200Y653900D02*
X138900Y654200D01*
X133300D01*
X128395Y649295D01*
Y646029D01*
G01X131135Y639554D02*
Y637435D01*
X125500Y631800D01*
X109965D01*
X108479Y630314D01*
X102835D01*
G01Y636219D02*
X99085D01*
X97300Y638004D01*
Y647551D01*
X86443Y658408D01*
Y662853D01*
G01X102835Y638189D02*
X99590D01*
X99050Y638729D01*
Y648276D01*
X88967Y658359D01*
Y659749D01*
G01X90674Y663367D02*
Y662969D01*
X91700Y661943D01*
Y658101D01*
X102835Y646966D01*
Y640154D01*
G01X136235Y632284D02*
X142751D01*
X150345Y624690D01*
X154590D01*
X156700Y626800D01*
G01X139929Y604165D02*
X140775Y605011D01*
Y616935D01*
X139206Y618504D01*
X136235D01*
G01X144329Y598765D02*
X142525Y600569D01*
Y617660D01*
X139716Y620469D01*
X136235D01*
G01X151029Y627565D02*
X150072D01*
X143388Y634249D01*
X136235D01*
G01X160700Y615900D02*
X158700D01*
X153410Y621190D01*
X148895D01*
X141741Y628344D01*
X136235D01*
G01X112800Y653500D02*
Y652573D01*
X114615Y650758D01*
Y646029D01*
G01X108200Y655825D02*
Y652223D01*
X110675Y649748D01*
Y646029D01*
G01X99578Y605771D02*
X98800Y606549D01*
Y620100D01*
X99169Y620469D01*
X102835D01*
G01Y628344D02*
X93790D01*
X93063Y629071D01*
Y629134D01*
G01X89435Y635029D02*
Y632762D01*
X93063Y629134D01*
G01X122088Y665912D02*
Y656311D01*
X120520Y654743D01*
Y646029D01*
G01X115600Y656750D02*
X115400Y656550D01*
Y652448D01*
X116580Y651268D01*
Y646029D01*
G01X111400Y658500D02*
Y655600D01*
X110625Y654825D01*
Y652273D01*
X112645Y650253D01*
Y646029D01*
G01X108710D02*
X107771D01*
X101900Y651900D01*
Y654100D01*
G01X136235Y624409D02*
X140726D01*
X146200Y618935D01*
Y616159D01*
X150023Y612336D01*
X160814D01*
X162125Y611025D01*
Y611024D01*
X163574Y609575D01*
X163575D01*
X164600Y608550D01*
G01X102835Y618504D02*
X107504D01*
X110035Y621035D01*
Y621136D01*
X113306Y624407D01*
X113403D01*
X113405Y624409D01*
X136235D01*
G01X122500Y653650D02*
X122490Y653640D01*
Y646029D01*
G01X118550D02*
Y651950D01*
X117400Y653100D01*
G01X136235Y630314D02*
X142246D01*
X149620Y622940D01*
X155060D01*
X157200Y620800D01*
G01X136235Y636219D02*
X144495D01*
X146663Y634051D01*
G01X92971Y617335D02*
Y619871D01*
X97509Y624409D01*
X102835D01*
G01X136235Y626374D02*
X141236D01*
X148595Y619015D01*
Y618300D01*
G01X125202Y657500D02*
X124455Y656753D01*
Y646029D01*
G01X92465Y610421D02*
X90425Y612461D01*
Y622105D01*
X91463Y623143D01*
G01X102835Y626374D02*
X94694D01*
X91463Y623143D01*
G01X136235Y640154D02*
X140754D01*
X145200Y644600D01*
G01X148435Y649879D02*
Y643735D01*
X142889Y638189D01*
X136235D01*
G01Y622439D02*
X140221D01*
X144400Y618260D01*
Y613236D01*
X146365Y611271D01*
G01X129000Y653600D02*
X133535Y658135D01*
Y658579D01*
G01X126425Y646029D02*
Y651025D01*
X129000Y653600D01*
G01X129335Y662079D02*
Y666136D01*
X132488Y669289D01*
X138788D01*
X142648Y665429D01*
G01X121500Y683500D02*
X125641D01*
X125806Y683665D01*
G01X113306Y682415D02*
X120415D01*
X121500Y683500D01*
G01X113306Y687415D02*
X119076D01*
X119483Y687008D01*
X119576D01*
G01D02*
X124749D01*
X125806Y688065D01*
G01X120702Y690847D02*
X124588D01*
X125906Y692165D01*
G01X113306Y692415D02*
X119134D01*
X120702Y690847D01*
G01X93206Y677415D02*
Y672544D01*
X94750Y671000D01*
G01X100600Y670600D02*
X95150D01*
X94750Y671000D01*
G01X116300Y667150D02*
X120850D01*
X122088Y665912D01*
G01X115600Y656750D02*
X119150D01*
X119300Y656600D01*
G01X104900Y658750D02*
X111150D01*
X111400Y658500D01*
G01X86060Y695200D02*
Y693255D01*
X86900Y692415D01*
X93206D01*
G01Y687415D02*
X88485D01*
X86000Y689900D01*
G01X93206Y682415D02*
X87909D01*
X86597Y681103D01*
G01X100200Y663900D02*
X101500Y665200D01*
X104400D01*
X107800Y668600D01*
X110850D01*
X112850Y670600D01*
G01X129335Y658579D02*
X126281D01*
X125202Y657500D01*
G01X133535Y658579D02*
X137723D01*
X137765Y658621D01*
G01X116350Y670600D02*
X116300D01*
X114425Y668725D01*
Y665875D01*
X116900Y663400D01*
X118127D01*
G01D02*
X119050Y662477D01*
Y660200D01*
G01X104900Y662250D02*
X104850Y662200D01*
G01X109005Y665890D02*
X108540D01*
X104900Y662250D01*
G01X95200D02*
X95950Y661500D01*
X104150D01*
X104850Y662200D01*
G01X115550Y660200D02*
X114000Y661750D01*
Y663350D01*
G01D02*
X109500D01*
X108350Y662200D01*
G01X105940Y846304D02*
Y841241D01*
X106404Y840777D01*
Y840700D01*
G01X100825Y846304D02*
Y841525D01*
X100300Y841000D01*
G01X111060Y846304D02*
Y851160D01*
X111500Y851600D01*
G01X98700Y877100D02*
X101500Y874300D01*
Y874200D01*
G01X102300Y863438D02*
X103380Y864518D01*
Y868504D01*
G01X108500D02*
Y863621D01*
X107164Y862285D01*
G01X113620Y868504D02*
Y862420D01*
X113400Y862200D01*
G01X110500Y939750D02*
Y942500D01*
X106050Y946950D01*
Y951350D01*
X108200Y953500D01*
G01D02*
X110494Y955794D01*
X112529D01*
G01D02*
X113960Y957225D01*
Y963000D01*
G01X112984Y946835D02*
X115054Y948905D01*
Y953554D01*
X117294Y955794D01*
X117529D01*
G01D02*
X116520Y956803D01*
Y963000D01*
G01X112984Y946835D02*
X112800Y946651D01*
Y944250D01*
X117300Y939750D01*
G01X120054Y945600D02*
Y941423D01*
X121671Y939806D01*
G01X119080Y963000D02*
Y959243D01*
X122529Y955794D01*
G01D02*
X122528D01*
X120054Y953320D01*
Y945600D01*
G01X131500Y947850D02*
Y949500D01*
X130000Y951000D01*
Y957275D01*
X130903Y958178D01*
G01D02*
Y958403D01*
X132000Y959500D01*
X137340D01*
G01X133500Y953000D02*
Y950350D01*
X136000Y947850D01*
G01X133500Y953000D02*
X135500Y955000D01*
X139500D01*
X139900Y955400D01*
Y959500D01*
G01X123300Y1001350D02*
Y1001400D01*
X140798Y1018898D01*
X142998D01*
X143000Y1018900D01*
X146800D01*
G01X135000Y1003250D02*
Y1005500D01*
X146800Y1017300D01*
Y1018900D01*
G01X119300Y1001350D02*
X138898Y1020948D01*
X142148D01*
X143900Y1022700D01*
G01X110400Y997850D02*
X114800D01*
G01D02*
Y997720D01*
X116520Y996000D01*
Y985200D01*
G01X119300Y997850D02*
X119080Y997630D01*
Y992900D01*
G01D02*
Y985200D01*
G01X123300Y997850D02*
X123850Y998400D01*
X127700D01*
G01X121640Y985200D02*
Y996190D01*
X123300Y997850D01*
G01X139900Y981700D02*
Y989200D01*
X136475Y992625D01*
Y998275D01*
X135000Y999750D01*
G01D02*
X134150D01*
X130900Y1003000D01*
Y1003400D01*
G01X88502Y1136247D02*
Y1139148D01*
X86950Y1140700D01*
Y1143000D01*
G01X112018Y1263718D02*
X116782D01*
X119500Y1261000D01*
G01X112018Y1255968D02*
X119000D01*
G01X104518Y1259843D02*
X108143D01*
X112018Y1255968D01*
G01X113800Y1399700D02*
X111600D01*
X111000Y1400300D01*
Y1404400D01*
X111600Y1405000D01*
X113050D01*
X115350Y1407300D01*
Y1408200D01*
G01X128700Y1408000D02*
X127129Y1406429D01*
X123171D01*
X121400Y1408200D01*
X115350D01*
G01X135601Y1416200D02*
X134900D01*
X132500Y1418600D01*
X126200D01*
X124050Y1420750D01*
X123000D01*
G01X134500Y1420000D02*
X133800Y1420700D01*
X127550D01*
X127500Y1420750D01*
G01X95600Y1420250D02*
X91500D01*
G01X98500Y1428400D02*
X98100Y1428000D01*
Y1421500D01*
X96850Y1420250D01*
X95600D01*
G01X135000Y1408354D02*
Y1404354D01*
X134700Y1404054D01*
G01X135696Y1392300D02*
X137500Y1394104D01*
Y1402000D01*
X135446Y1404054D01*
X134700D01*
G01X121125Y1401954D02*
X119500Y1400329D01*
Y1392000D01*
X117000Y1389500D01*
Y1387500D01*
G01D02*
X119000Y1385500D01*
X122862D01*
G01D02*
X141000D01*
X143000Y1387500D01*
G01D02*
X139500Y1391000D01*
X136996D01*
X135696Y1392300D01*
G01X135000Y1411854D02*
X139342D01*
X141100Y1410096D01*
G01X129000Y1416425D02*
X131475D01*
X135000Y1412900D01*
Y1411854D01*
G01X113800Y1402260D02*
X115740D01*
X117399Y1400601D01*
Y1394000D01*
X115399Y1392000D01*
X99000D01*
X97500Y1390500D01*
Y1382500D01*
X99500Y1380500D01*
X165000D01*
G01X99500Y1407500D02*
X100100Y1408100D01*
X104050D01*
G01D02*
Y1406550D01*
X105600Y1405000D01*
X107700D01*
X109200Y1403500D01*
Y1400600D01*
G01D02*
Y1397940D01*
X108400Y1397140D01*
X106400D01*
G01Y1399700D02*
X108300D01*
X109200Y1400600D01*
G01X117100Y1430100D02*
X118000Y1429200D01*
Y1424250D01*
G01X119559Y1442400D02*
Y1432559D01*
X117100Y1430100D01*
G01X109500Y1438000D02*
X112575D01*
X114441Y1439866D01*
Y1442400D01*
G01X123000Y1424250D02*
Y1431300D01*
G01D02*
Y1441518D01*
X122118Y1442400D01*
G01X127500Y1424250D02*
X126975Y1424775D01*
Y1435400D01*
G01D02*
Y1446357D01*
X127013Y1446395D01*
Y1446469D01*
X126600Y1446882D01*
G01X133250Y1428300D02*
X135050Y1426500D01*
X136894D01*
X138694Y1424700D01*
Y1422269D01*
G01X133250Y1428300D02*
Y1432000D01*
G01X147500Y1437250D02*
X144954D01*
X139704Y1432000D01*
X133250D01*
G01X182588Y542288D02*
X175776Y549100D01*
X172100D01*
G01D02*
X170100D01*
X165900Y553300D01*
G01X158000Y575150D02*
X157100Y574250D01*
Y565400D01*
X160000Y562500D01*
G01X165900Y553300D02*
X160300Y558900D01*
Y559000D01*
X154750Y564550D01*
Y565300D01*
X153500Y566550D01*
G01X153135Y559250D02*
Y566185D01*
X153500Y566550D01*
G01X147900Y588100D02*
X151650D01*
X152750Y587000D01*
G01X152700Y618803D02*
Y618700D01*
X155779Y615621D01*
Y615065D01*
G01X170200Y623650D02*
Y620098D01*
X170349Y619949D01*
G01X151432Y661741D02*
X149092D01*
X145800Y658449D01*
Y654944D01*
X144235Y653379D01*
G01X148435D02*
Y658008D01*
X148995Y658568D01*
G01X180365Y645821D02*
Y646635D01*
X174100Y652900D01*
G01X171370Y645839D02*
Y650170D01*
X174100Y652900D01*
G01X170100Y607600D02*
X175265D01*
X176300Y608635D01*
G01X170100Y607600D02*
X165550D01*
X164600Y608550D01*
G01X176221Y613535D02*
Y608714D01*
X176300Y608635D01*
G01X162650Y622700D02*
X160750Y620800D01*
X157200D01*
G01X151335Y632379D02*
X148335D01*
X146663Y634051D01*
G01X148595Y618300D02*
X151830Y615065D01*
X152279D01*
G01X151335Y640400D02*
Y635879D01*
G01X159800Y634819D02*
X152395D01*
X151335Y635879D01*
G01X145200Y644600D02*
X146383Y645783D01*
Y648684D01*
X145188Y649879D01*
X144235D01*
G01X153200Y653200D02*
X149879Y649879D01*
X148435D01*
G01X146365Y611271D02*
X147390Y610246D01*
X147391D01*
X148666Y608971D01*
X152265D01*
G01D02*
X157627D01*
X158535Y609879D01*
G01X163100Y604717D02*
Y605314D01*
X158535Y609879D01*
G01X166150Y626700D02*
Y622700D01*
G01X170200Y627150D02*
X166600D01*
X166150Y626700D01*
G01X170200Y627150D02*
X171400D01*
X174250Y624300D01*
G01X179017Y620013D02*
X177487D01*
X174250Y623250D01*
Y624300D01*
G01X154500Y687250D02*
X151550D01*
X151025Y687775D01*
X150978D01*
G01X158500Y695000D02*
X159515Y696015D01*
X159633D01*
X160500Y696882D01*
Y699000D01*
X163300Y701800D01*
Y702300D01*
G01X163500Y710104D02*
Y702500D01*
X163300Y702300D01*
G01X158500Y702750D02*
X162850D01*
X163300Y702300D01*
G01X161500Y691700D02*
X158500Y694700D01*
Y695000D01*
G01X150700Y691700D02*
X149904Y690904D01*
X148504D01*
X147350Y689750D01*
X145500D01*
G01X153192Y705890D02*
Y705308D01*
X154500Y704000D01*
Y702750D01*
G01D02*
X157250Y705500D01*
X160000D01*
X160940Y706440D01*
Y710104D01*
G01X144250Y695500D02*
Y691000D01*
X145500Y689750D01*
G01X141625Y682250D02*
Y677875D01*
X144500Y675000D01*
X145500D01*
G01D02*
X146000Y674500D01*
X152500D01*
X153000Y675000D01*
Y682250D01*
X154500Y683750D01*
G01X171750Y701100D02*
X169150D01*
X167700Y699650D01*
G01X166060Y710104D02*
Y704840D01*
X167600Y703300D01*
G01X167700Y699650D02*
Y703200D01*
X167600Y703300D01*
G01X168620Y710104D02*
Y706780D01*
X169800Y705600D01*
X178100D01*
X179000Y706500D01*
G01X155825Y710104D02*
X151146D01*
X149500Y711750D01*
G01D02*
X145000D01*
G01X143000Y953032D02*
Y953525D01*
X145020Y955545D01*
Y959500D01*
G01X143000Y953032D02*
Y951250D01*
X145000Y949250D01*
G01X147580Y959500D02*
Y954110D01*
X146500Y953030D01*
G01D02*
Y951750D01*
X149000Y949250D01*
G01X150140Y959500D02*
Y954829D01*
X149772Y954461D01*
Y954121D01*
G01D02*
Y953917D01*
X150830Y952859D01*
Y951420D01*
X153000Y949250D01*
G01X152700Y959500D02*
Y952521D01*
X152747Y952474D01*
G01D02*
X153776D01*
X157000Y949250D01*
G01X142460Y959500D02*
Y955460D01*
X139500Y952500D01*
Y951500D01*
G01D02*
Y948850D01*
X140500Y947850D01*
G01X139100Y1003150D02*
Y1006200D01*
X148975Y1016075D01*
Y1019801D01*
X146076Y1022700D01*
X143900D01*
G01X152700Y981700D02*
Y987450D01*
X159500Y994250D01*
G01X152700Y981700D02*
Y978700D01*
X150500Y976500D01*
G01X155260Y981700D02*
Y974760D01*
X155000Y974500D01*
G01X155260Y981700D02*
Y986260D01*
X163250Y994250D01*
X163500D01*
G01X147580Y981700D02*
Y994580D01*
X147600Y994600D01*
G01X147900Y999650D02*
Y994900D01*
X147600Y994600D01*
G01X143100Y1007100D02*
Y1007000D01*
X141150Y1005050D01*
Y1001250D01*
X139550Y999650D01*
X139100D01*
G01D02*
Y992900D01*
X142500Y989500D01*
Y981740D01*
X142460Y981700D01*
G01X145020D02*
Y991480D01*
X142000Y994500D01*
G01X143800Y999750D02*
Y996300D01*
X142000Y994500D01*
G01X150140Y981700D02*
Y990640D01*
X154000Y994500D01*
G01X152100Y999750D02*
Y996400D01*
X154000Y994500D01*
G01X155550Y1423400D02*
X156300D01*
X169900Y1409800D01*
Y1375400D01*
X165000Y1370500D01*
G01X142500Y1420500D02*
X143900Y1421900D01*
Y1425800D01*
X156104Y1438004D01*
X158600D01*
G01X142500Y1420500D02*
X140731Y1422269D01*
X138694D01*
G01X159774Y1414374D02*
X159148Y1415000D01*
X155546D01*
G01X151900Y1408954D02*
X148358D01*
X141100Y1401696D01*
G01X155546Y1415000D02*
Y1412600D01*
X151900Y1408954D01*
G01X151454Y1394000D02*
X161500D01*
X165000Y1390500D01*
G01X151454Y1394000D02*
X151100Y1394354D01*
Y1398100D01*
X148025Y1401175D01*
Y1401454D01*
G01X155546Y1419200D02*
X158025D01*
X163500Y1413725D01*
Y1406600D01*
X162000Y1405100D01*
X149300D01*
X148025Y1403825D01*
Y1401454D01*
G01X152331Y1431131D02*
X156631D01*
G01D02*
X160891Y1435391D01*
Y1444113D01*
X158600Y1446404D01*
G01X165500Y1450600D02*
X168369D01*
X169369Y1449600D01*
Y1444969D01*
G01X158600Y1446404D02*
X159696Y1447500D01*
X160500D01*
X163600Y1450600D01*
X165500D01*
G01X160831Y1426831D02*
X157431D01*
X156631Y1427631D01*
G01D02*
Y1424481D01*
X155550Y1423400D01*
G54D10*
G01X67250Y63500D02*
Y62045D01*
X63315Y58110D01*
X15906D01*
G01X27000Y573800D02*
X27100Y573900D01*
X29000D01*
X30000Y572900D01*
Y571176D01*
X29950Y571126D01*
Y570800D01*
G01X15906Y751181D02*
X19000Y748087D01*
Y743500D01*
X23500Y739000D01*
X52500D01*
X61500Y730000D01*
X65250D01*
G01X15906Y1197323D02*
X18883D01*
X46475Y1169731D01*
Y1022525D01*
X51000Y1018000D01*
G01X15906Y1890394D02*
X30106D01*
X56025Y1864475D01*
Y1809125D01*
X39206Y1792306D01*
X39179D01*
G01X67250Y63500D02*
X63500D01*
G01X87400Y574150D02*
X86650Y574900D01*
X86300D01*
X83619Y577581D01*
Y581742D01*
G01X82900Y574500D02*
X83650Y573750D01*
Y569900D01*
G01X78600Y571050D02*
X78950D01*
X82400Y574500D01*
X82900D01*
G01X83650Y569900D02*
Y568850D01*
X85400Y567100D01*
Y561050D01*
G01X83430D02*
Y565370D01*
X80600Y568200D01*
X76300D01*
X74100Y570400D01*
G01D02*
X70400Y566700D01*
Y565500D01*
G01X65250Y730000D02*
X65500Y729750D01*
Y726481D01*
X67981Y724000D01*
X86000D01*
X86500Y723500D01*
G01X51200Y827000D02*
X53000Y825200D01*
X108050D01*
X111200Y828350D01*
G01X61207D02*
X98800D01*
X98804Y828346D01*
X102900D01*
G01X102600Y884850D02*
X69750D01*
X67600Y882700D01*
X64600D01*
G01X110900Y884850D02*
X106800D01*
X104600Y887050D01*
X68838D01*
X66988Y885200D01*
X61600D01*
G01X119300Y884850D02*
X115100D01*
Y885000D01*
X110700Y889400D01*
X67800D01*
X67200Y888800D01*
G01X81850Y966200D02*
X82150Y965900D01*
X87600D01*
G01X70800Y981600D02*
X72350Y980050D01*
X77400D01*
G01X76800Y986600D02*
X80800D01*
X81500Y985900D01*
G01X77400Y980050D02*
Y981900D01*
X81400Y985900D01*
X81500D01*
G01X51000Y1018000D02*
X51500Y1017500D01*
X68950D01*
X72350Y1020900D01*
G01X68750Y1175100D02*
Y1178750D01*
X68800Y1178800D01*
G01X83500Y1461750D02*
X89450D01*
X89500Y1461700D01*
G01X78752Y1619703D02*
X83000D01*
G01X78752Y1613297D02*
X78797D01*
X81500Y1616000D01*
X83050D01*
G01X39179Y1792306D02*
X38606D01*
X34950Y1788650D01*
Y1788200D01*
G01X87370Y544750D02*
Y538320D01*
X86850Y537800D01*
G01X89335Y544750D02*
Y538815D01*
X90350Y537800D01*
G01X87150Y569900D02*
X87370Y569680D01*
Y561050D01*
G01X87150Y569900D02*
Y573900D01*
X87400Y574150D01*
G01X135200Y566400D02*
X135400Y566600D01*
X140400D01*
G01X116175Y846304D02*
Y843225D01*
X118700Y840700D01*
G01X111060Y868504D02*
Y863211D01*
X106987Y859138D01*
X95762D01*
X93900Y861000D01*
X87950D01*
X87450Y861500D01*
G01X113620Y846304D02*
Y840180D01*
X116800Y837000D01*
X119300D01*
G01D02*
X119600Y836700D01*
Y831850D01*
G01X87446Y852900D02*
X92300D01*
X94138Y854738D01*
X111362D01*
X113600Y852500D01*
Y852300D01*
X113620Y852280D01*
Y846304D01*
G01X116175Y868504D02*
Y861375D01*
X111738Y856938D01*
X93862D01*
X92700Y858100D01*
G01X87450Y857200D02*
X91800D01*
X92700Y858100D01*
G01X108500Y846304D02*
Y841770D01*
X108504Y841766D01*
Y839634D01*
X108502Y839632D01*
Y834518D01*
X110620Y832400D01*
X110650D01*
X111200Y831850D01*
G01X87446Y848500D02*
X92000D01*
X92400Y848900D01*
G01D02*
X96038Y852538D01*
X106262D01*
X108500Y850300D01*
Y846304D01*
G01X103380D02*
Y849420D01*
X102462Y850338D01*
X98038D01*
X91800Y844100D01*
X87446D01*
G01X103400Y838300D02*
X103380Y838320D01*
Y846304D01*
G01X102900Y831846D02*
X103400Y832346D01*
Y838300D01*
G01X119600Y828350D02*
X119150D01*
X114900Y824100D01*
G01X87450Y865700D02*
X92400D01*
X92800Y865300D01*
G01X102600Y881350D02*
X103565Y880385D01*
Y876465D01*
X105940Y874090D01*
Y868504D01*
G01D02*
Y864108D01*
X103170Y861338D01*
X96762D01*
X92800Y865300D01*
G01X111100Y876700D02*
X111060Y876660D01*
Y868504D01*
G01X110900Y881350D02*
X111060Y881190D01*
Y876740D01*
X111100Y876700D01*
G01X119300Y881350D02*
X116175Y878225D01*
Y868504D01*
G01X103500Y966500D02*
Y964000D01*
X97000Y957500D01*
X94500D01*
G01D02*
X94000Y957000D01*
G01X130800Y981600D02*
Y985800D01*
X129900Y986700D01*
G01X88000Y972550D02*
Y966300D01*
X87600Y965900D01*
G01X99000Y979750D02*
X103250D01*
X103500Y980000D01*
G01X99000Y979750D02*
X97250D01*
X94500Y982500D01*
G01D02*
Y984000D01*
X90542Y987958D01*
G01D02*
X89958D01*
X88000Y986000D01*
Y980050D01*
G01X97958Y966958D02*
X94000Y963000D01*
G01X99000Y976250D02*
Y968000D01*
X97958Y966958D01*
G01X103500Y974000D02*
Y966500D01*
G01X100500Y1420250D02*
Y1417500D01*
X99600Y1416600D01*
Y1416500D01*
G01X113150Y1421600D02*
Y1425900D01*
G01X131174Y1412700D02*
X128246D01*
X125000Y1409454D01*
G01X100000Y1443000D02*
Y1444154D01*
X105287Y1449441D01*
X107400D01*
G01X94750Y1434900D02*
X100000Y1440150D01*
Y1443000D01*
G01X111833Y1469667D02*
Y1468367D01*
X114441Y1465759D01*
Y1461600D01*
G01X107000Y1474500D02*
X107100D01*
X111833Y1469767D01*
Y1469667D01*
G01X95500Y1460750D02*
X90450D01*
X89500Y1461700D01*
G01X95500Y1460750D02*
X101000D01*
G01D02*
Y1460500D01*
X104382Y1457118D01*
X107400D01*
G01X91250Y1451000D02*
X86900D01*
G01X93500Y1475750D02*
Y1475000D01*
X101500Y1467000D01*
X109500D01*
X111882Y1464618D01*
Y1461600D01*
G01X100200Y1433800D02*
X97900Y1431500D01*
X94750D01*
G01X107400Y1446882D02*
Y1443900D01*
X100200Y1436700D01*
Y1433800D01*
G01X126600Y1449441D02*
X130223D01*
X132064Y1447600D01*
X133000D01*
G01D02*
X133100D01*
X138800Y1453300D01*
X140150D01*
G01X111882Y1442400D02*
X109900D01*
X104500Y1437000D01*
Y1431000D01*
X103000Y1429500D01*
G01X109650Y1425900D02*
Y1429150D01*
X110000Y1429500D01*
G01X105000Y1423750D02*
X107500D01*
X109650Y1425900D01*
G01X100500Y1423750D02*
X105000D01*
G01X103000Y1429500D02*
X100500Y1427000D01*
Y1423750D01*
G01X132000Y1436500D02*
X140071D01*
X147000Y1443429D01*
Y1445071D01*
X150929Y1449000D01*
X154000D01*
X155000Y1450000D01*
X160000D01*
X163000Y1453000D01*
X168763D01*
X171869Y1449894D01*
Y1441869D01*
X167469Y1437469D01*
X165494D01*
G01X117000Y1461600D02*
Y1479800D01*
X121300Y1484100D01*
Y1497950D01*
X121000Y1498250D01*
G01X125000D02*
X123750Y1497000D01*
Y1483250D01*
X119559Y1479059D01*
Y1461600D01*
G01X113150Y1425900D02*
Y1431350D01*
X117000Y1435200D01*
G01X133799Y1440699D02*
X134248Y1440250D01*
X137500D01*
G01X117000Y1435200D02*
Y1442400D01*
G01X106770Y1480640D02*
Y1486020D01*
X107500Y1486750D01*
G01X107000Y1474500D02*
X106770Y1474730D01*
Y1480640D01*
G01X87800Y1477500D02*
Y1477450D01*
X89500Y1475750D01*
X93500D01*
G01X87750Y1484000D02*
Y1477550D01*
X87800Y1477500D01*
G01X91300Y1488600D02*
X87750Y1485050D01*
Y1484000D01*
G01X104333Y1498167D02*
X108917D01*
X109000Y1498250D01*
G01D02*
X113000D01*
G01D02*
X117000D01*
G01D02*
X121000D01*
G01X142400Y1499900D02*
X140800Y1498300D01*
X137050D01*
X137000Y1498250D01*
G01X133000D02*
X137000D01*
G01X129000D02*
X133000D01*
G01X125000D02*
X129000D01*
G01X121000Y1501750D02*
Y1506500D01*
G01X113000Y1501750D02*
Y1506500D01*
G01X117000Y1501750D02*
Y1506500D01*
G01X109000Y1501750D02*
Y1506500D01*
G01X133000Y1501750D02*
Y1505500D01*
G01X129000Y1501750D02*
Y1506498D01*
X128999Y1506499D01*
G01X125000Y1501750D02*
Y1506500D01*
G01X135008Y1508245D02*
X136255D01*
X137000Y1507500D01*
Y1501750D01*
G01X109252Y1619703D02*
Y1620252D01*
X111800Y1622800D01*
X113200D01*
G01X109252Y1613297D02*
Y1613852D01*
X113200Y1617800D01*
Y1619300D01*
G01X148750Y568000D02*
X149300Y568550D01*
Y574400D01*
X149500Y574600D01*
G01X151170Y559250D02*
Y565580D01*
X148750Y568000D01*
G01X149500Y574600D02*
X149300Y574800D01*
Y578450D01*
X149500Y578650D01*
G01X149200Y559250D02*
Y564050D01*
X145250Y568000D01*
G01X145230Y571700D02*
X145696Y571234D01*
Y568446D01*
X145250Y568000D01*
G01X145300Y578750D02*
Y571770D01*
X145230Y571700D01*
G01X140400Y566600D02*
X143100D01*
X147230Y562470D01*
Y559250D01*
G01X155200Y679500D02*
X159900Y684200D01*
X173305D01*
X177200Y688095D01*
Y693050D01*
X175250Y695000D01*
Y701100D01*
G01X165494Y1437469D02*
Y1430344D01*
X165400Y1430250D01*
G01D02*
X165319Y1430331D01*
X160831D01*
G01X143625Y1444750D02*
X141750D01*
X138000Y1448500D01*
G01X143625Y1444750D02*
X144500Y1445625D01*
Y1446769D01*
X149231Y1451500D01*
X152756D01*
X153456Y1452200D01*
X158012D01*
X160000Y1454188D01*
Y1455250D01*
X160750Y1456000D01*
Y1458000D01*
G01D02*
X166700D01*
X167000Y1457700D01*
G01X137500Y1443750D02*
Y1448000D01*
X138000Y1448500D01*
G01X157500Y1454800D02*
Y1457750D01*
X157250Y1458000D01*
G01X151375Y1444750D02*
X151500Y1444625D01*
Y1438500D01*
G01X160500Y1462500D02*
Y1461250D01*
X157250Y1458000D01*
G01X142569Y1429769D02*
X144969D01*
X151500Y1436300D01*
Y1438500D01*
G01X137752Y1619703D02*
Y1621652D01*
X141100Y1625000D01*
X141300D01*
G01X165252Y1619703D02*
X166703D01*
X169876Y1622876D01*
Y1626303D01*
G01X137752Y1613297D02*
Y1613752D01*
X141300Y1617300D01*
Y1621400D01*
X141500Y1621600D01*
G01X165252Y1613297D02*
Y1614049D01*
X173000Y1621797D01*
Y1626382D01*
X173135Y1626517D01*
X173270D01*
X-222440Y19685D03*
Y1948818D03*
X29921Y24803D03*
Y111417D03*
Y458031D03*
Y544646D03*
Y717874D03*
Y804488D03*
X30000Y1164000D03*
X29921Y1250630D03*
Y1423858D03*
Y1510472D03*
Y1857086D03*
Y1943701D03*
X47244Y68110D03*
X80709Y119409D03*
Y139409D03*
Y329409D03*
Y309409D03*
X47244Y501338D03*
Y761181D03*
Y1207323D03*
Y1467165D03*
Y1900393D03*
X149606Y119409D03*
Y139409D03*
Y329409D03*
Y309409D03*
X643700Y19685D03*
Y1948818D03*
G54D20*
X32700Y253500D03*
X19283Y307282D03*
X32900Y1660800D03*
X25900Y1721700D03*
X56600Y191600D03*
X57400Y207900D03*
X56900Y236600D03*
X63000Y264300D03*
X39200Y343800D03*
X81400Y530500D03*
X78400Y587600D03*
X49600Y573500D03*
X61400Y673400D03*
X57400D03*
X64100Y909400D03*
X77002Y1134497D03*
X83500Y1461800D03*
X96100Y530500D03*
X124900Y585204D03*
X120800D03*
X93065Y594071D03*
X97265D03*
X92465Y606971D03*
X95200Y662300D03*
X110900Y881400D03*
X102600D03*
X119300D03*
X122529Y952344D03*
X117529D03*
X112529D03*
X100500Y1420300D03*
X91500D03*
X105000D03*
X135000Y1408404D03*
X134700Y1400604D03*
X107500Y1486800D03*
X170600Y529100D03*
X155600Y529000D03*
X158000Y575200D03*
X170200Y623700D03*
X180365Y642371D03*
X137765Y658671D03*
X154500Y683800D03*
X149500Y708300D03*
X147900Y999700D03*
X152100Y999800D03*
X163500Y994300D03*
X159500D03*
X143800Y999800D03*
X137500Y1440300D03*
G54D11*
X-181139Y20007D03*
X-180444Y1947256D03*
X150000Y64500D03*
X152500Y1906000D03*
X601704Y21248D03*
X602399Y1948497D03*
G54D21*
X32700Y256900D03*
X19283Y310682D03*
X32900Y1664200D03*
X25900Y1725100D03*
X56600Y195000D03*
X57400Y211300D03*
X56900Y240000D03*
X63000Y267700D03*
X39200Y347200D03*
X81400Y533900D03*
X78400Y591000D03*
X49600Y576900D03*
X61400Y676800D03*
X57400D03*
X64100Y912800D03*
X77002Y1137897D03*
X83500Y1465200D03*
X96100Y533900D03*
X124900Y588604D03*
X120800D03*
X93065Y597471D03*
X97265D03*
X92465Y610371D03*
X95200Y665700D03*
X110900Y884800D03*
X102600D03*
X119300D03*
X122529Y955744D03*
X117529D03*
X112529D03*
X135000Y1411804D03*
X134700Y1404004D03*
X100500Y1423700D03*
X91500D03*
X105000D03*
X107500Y1490200D03*
X170600Y532500D03*
X155600Y532400D03*
X158000Y578600D03*
X170200Y627100D03*
X180365Y645771D03*
X137765Y662071D03*
X154500Y687200D03*
X149500Y711700D03*
X147900Y1003100D03*
X152100Y1003200D03*
X163500Y997700D03*
X159500D03*
X143800Y1003200D03*
X137500Y1443700D03*
G54D30*
X24100Y690900D03*
X28900D03*
X74100Y576200D03*
X65635Y693906D03*
X70535D03*
X82000Y708200D03*
X72200Y711000D03*
X67200D03*
X70800Y981400D03*
X64200Y1004100D03*
X81398Y1137753D03*
X92300Y878454D03*
X87500D03*
X94000Y962800D03*
X103500Y979800D03*
X129900Y992500D03*
X140400Y572400D03*
X158535Y609679D03*
G54D12*
X8594Y6500D03*
X31500Y5500D03*
X20000Y6000D03*
X17000Y36500D03*
X32000Y40000D03*
X5594Y87000D03*
Y53500D03*
X29500Y53000D03*
X26000Y87000D03*
X30800Y130300D03*
X4594Y120500D03*
X34400Y95300D03*
X14000Y141000D03*
X23500Y124000D03*
X15000Y131500D03*
X14500Y100500D03*
Y112500D03*
X4500Y105500D03*
X5000Y137500D03*
X22500Y190000D03*
X29700Y191400D03*
X5594Y153500D03*
X4594Y187500D03*
X16500Y175000D03*
X27000Y182000D03*
X14000Y184000D03*
X4500Y170500D03*
X21500Y241500D03*
X4594Y234000D03*
X24000Y212000D03*
X29000Y200500D03*
X13000Y244000D03*
X13500Y230500D03*
X13000Y212500D03*
X5000Y221000D03*
X12500Y197500D03*
X4500Y202500D03*
X28050Y256950D03*
X18600Y249100D03*
X5094Y278000D03*
X6094Y257000D03*
X13500Y279000D03*
Y295000D03*
X5500Y295500D03*
X12500Y266500D03*
X5500Y269500D03*
X5000Y247500D03*
X19721Y267203D03*
X27900Y269471D03*
X5594Y312000D03*
X5304Y342500D03*
X4900Y328000D03*
X13500Y303500D03*
X13000Y321000D03*
X20010Y302982D03*
X4594Y396500D03*
X6500Y375000D03*
X27000Y371000D03*
X4800Y356200D03*
X23700Y363900D03*
X29500Y364500D03*
X27000Y377500D03*
Y384000D03*
Y389500D03*
X4594Y421000D03*
X5304Y444500D03*
Y440500D03*
X5000Y408500D03*
X5304Y434500D03*
X26500Y440000D03*
X26000Y432500D03*
X23800Y410700D03*
X5094Y469500D03*
X5000Y495000D03*
X4700Y458200D03*
X5000Y486500D03*
X11000Y578000D03*
X27300Y593000D03*
X5094Y600000D03*
X34100Y566600D03*
X13510Y597990D03*
X27100Y578100D03*
X14000Y614000D03*
X4594Y625000D03*
X18000Y608000D03*
X6000Y612000D03*
Y646000D03*
X26000Y656500D03*
X5594Y688500D03*
X5304Y661000D03*
X14000Y659000D03*
X23000Y677500D03*
X32000Y666000D03*
X28000Y706000D03*
X8000Y678000D03*
X31000Y700500D03*
X20000Y696000D03*
X6000Y698000D03*
Y706500D03*
X31000Y747000D03*
X22000Y746000D03*
X24000Y756000D03*
X27000Y750000D03*
X26000Y732000D03*
X18000Y724000D03*
Y732500D03*
Y712000D03*
X6000Y722000D03*
Y730500D03*
X5594Y778000D03*
X6500Y799000D03*
X9500Y804000D03*
X30000Y782000D03*
X16100Y794600D03*
X5594Y844500D03*
X6094Y819500D03*
X30500D03*
X10000Y811500D03*
X24000Y846000D03*
X24500Y853500D03*
X16000Y828000D03*
Y814000D03*
Y856000D03*
Y842000D03*
X32000Y858000D03*
Y844000D03*
X4500Y833500D03*
Y857500D03*
X26053Y828247D03*
X5094Y897500D03*
X5594Y869000D03*
X16000Y906000D03*
X32000Y886000D03*
Y872000D03*
X18000Y884000D03*
Y870000D03*
X5000Y883500D03*
X18500Y896500D03*
X23053Y861247D03*
X5304Y926000D03*
X4594Y954000D03*
X18000Y934000D03*
Y920000D03*
X16000Y962000D03*
Y948000D03*
X4500Y913000D03*
Y941500D03*
X34000Y944000D03*
Y934500D03*
X33500Y962500D03*
Y953000D03*
X26053Y938247D03*
X4594Y1013500D03*
X5594Y984500D03*
X28000Y992000D03*
X26000Y1010000D03*
X16000Y990000D03*
Y976000D03*
Y1014000D03*
Y1000000D03*
X4500Y970000D03*
Y997000D03*
X34000Y984000D03*
Y974500D03*
Y1008000D03*
X25053Y971247D03*
X31600Y1024300D03*
X4594Y1041500D03*
X6000Y1058000D03*
X33600Y1029900D03*
X16000Y1046000D03*
Y1032000D03*
X14000Y1060000D03*
X4500Y1029500D03*
X34000Y1017500D03*
X27553Y1029247D03*
X5094Y1074500D03*
X32000Y1114000D03*
X34000Y1102000D03*
Y1072000D03*
X28000D03*
X14000Y1074000D03*
Y1100000D03*
Y1086000D03*
X16000Y1110000D03*
X6000Y1096000D03*
X26100Y1088600D03*
X27218Y1097000D03*
X33550Y1080100D03*
X24500Y1102000D03*
X34000Y1144000D03*
X16000Y1124000D03*
Y1148000D03*
Y1134000D03*
Y1162000D03*
X6000Y1138000D03*
Y1118000D03*
Y1152000D03*
X26600Y1132400D03*
X24553Y1153247D03*
X5304Y1208000D03*
X4594Y1169500D03*
X24000Y1180000D03*
X16000Y1176000D03*
X5094Y1268500D03*
X8500Y1237000D03*
X30000Y1240000D03*
X16000Y1262000D03*
Y1244000D03*
X28000Y1266000D03*
X6000Y1252000D03*
X22000Y1232000D03*
X31500Y1222000D03*
X6500Y1302000D03*
X17700Y1283000D03*
X34000Y1312000D03*
X6000Y1318000D03*
X12000Y1274000D03*
Y1294000D03*
X28000Y1286000D03*
Y1300000D03*
Y1320000D03*
X19800Y1315400D03*
X13500Y1365000D03*
X8000Y1368000D03*
X30800Y1403900D03*
X31500Y1397500D03*
X5304Y1409400D03*
X4594Y1382000D03*
X7500Y1376500D03*
X32000Y1391500D03*
X4800Y1460700D03*
X4594Y1435500D03*
X34000Y1465900D03*
X5304Y1504100D03*
Y1522100D03*
X4600Y1484800D03*
X34000Y1477600D03*
X29500Y1495800D03*
X33000Y1575000D03*
X5304Y1576200D03*
Y1540500D03*
X26600Y1570100D03*
X26900Y1547900D03*
Y1559100D03*
X4594Y1607500D03*
X33100Y1587400D03*
X26700Y1579800D03*
X7500Y1640200D03*
X5304Y1659000D03*
X4700Y1676100D03*
X4594Y1632000D03*
X29000Y1671000D03*
X19250Y1663100D03*
X32900Y1656300D03*
X13900Y1706200D03*
X5304Y1723500D03*
X4900Y1708000D03*
X13100Y1728900D03*
X4594Y1691000D03*
X33000Y1718500D03*
X32949Y1709451D03*
X30000Y1731000D03*
X4594Y1775000D03*
Y1751000D03*
X12600Y1753800D03*
X13100Y1742600D03*
X12900Y1765200D03*
X20056Y1774189D03*
X14500Y1832500D03*
X12600Y1792800D03*
X12500Y1782500D03*
X4594Y1878500D03*
X14500Y1863500D03*
X5000Y1864100D03*
X18600Y1871400D03*
X4594Y1850000D03*
X15000Y1854900D03*
X27500Y1883500D03*
X14500Y1842000D03*
X28000Y1876500D03*
X29000Y1841000D03*
X13100Y1933900D03*
X24800Y1926500D03*
X5094Y1921000D03*
X4594Y1902000D03*
X35000Y1933500D03*
X35300Y1925300D03*
X34500Y1963200D03*
X16100Y1950700D03*
X5094Y1944500D03*
X15500Y1942500D03*
X4500Y1936000D03*
X6500Y1962000D03*
X25000Y1962500D03*
X12500Y1959000D03*
X63594Y7000D03*
Y25500D03*
X40594Y6000D03*
X49000Y18500D03*
X43000Y27000D03*
X64500Y40000D03*
X64000Y17000D03*
X53000Y5000D03*
X51500Y53000D03*
X74000Y45000D03*
X85000D03*
X43900Y137200D03*
X63098Y119103D03*
X52000Y115600D03*
X62598Y141103D03*
X51700Y131700D03*
X71000Y131859D03*
X37000Y124000D03*
X51900Y145700D03*
X86000Y152000D03*
X69000Y153000D03*
X73500Y146000D03*
X60800Y147700D03*
X86000Y296000D03*
X68000D03*
X76000D03*
X68000Y286000D03*
Y320000D03*
Y312000D03*
Y304000D03*
X36200Y318700D03*
X63200Y385100D03*
X74000Y390000D03*
X66000D03*
X58000D03*
X74000Y400000D03*
X66000D03*
X58000D03*
X64000Y446500D03*
Y451000D03*
X62400Y430600D03*
X62900Y412900D03*
X61700Y421900D03*
X74000Y408000D03*
X66000D03*
Y418000D03*
X74000D03*
X73700Y423000D03*
X66000Y426000D03*
X58000D03*
Y408000D03*
Y417500D03*
X84500Y433000D03*
X58100Y431900D03*
X63096Y434540D03*
X68500Y434300D03*
X81000Y410500D03*
X86400D03*
X70900Y427200D03*
X78200Y501000D03*
X82000Y483600D03*
X46000Y490500D03*
X71900Y501000D03*
X50100Y493000D03*
X42500D03*
X78200Y481700D03*
X63300Y464400D03*
X64000Y455500D03*
Y460000D03*
X62500Y472900D03*
X62600Y468500D03*
X62500Y477000D03*
X66000Y510500D03*
X78500Y506700D03*
X71800Y506900D03*
X85000Y506400D03*
X84500Y514400D03*
X72100Y521800D03*
X79400D03*
X72000Y514800D03*
X78000D03*
X51700Y522500D03*
X74942Y530983D03*
X77400Y536300D03*
X72500Y595900D03*
X56800Y576950D03*
X36000Y554000D03*
X79122Y565700D03*
X79458Y578758D03*
X69800Y574200D03*
X83619Y581742D03*
X82900Y574500D03*
X70400Y565500D03*
X43337Y650145D03*
X49665Y642933D03*
X37000Y605000D03*
X80900Y668400D03*
X86443Y662853D03*
X84504Y666353D03*
X56710Y681069D03*
X39096Y674917D03*
X43281Y674991D03*
X40000Y659000D03*
X71800Y701300D03*
X69100Y698006D03*
X74100Y669398D03*
X86060Y695200D03*
X86000Y689900D03*
X57200Y667884D03*
X50000Y712500D03*
Y749000D03*
X40000Y746500D03*
X36000Y730000D03*
X46000Y726000D03*
X65000Y775000D03*
Y766000D03*
X82000Y806500D03*
X44000Y782000D03*
X42000Y802000D03*
Y788000D03*
X47600Y796800D03*
X79000Y857000D03*
X81500Y837500D03*
X82500Y814000D03*
X48000Y816000D03*
X38000Y834000D03*
Y820000D03*
X46000Y848000D03*
Y834000D03*
X78300Y832600D03*
X77600Y849100D03*
X87000Y839500D03*
X48100Y853400D03*
X45600Y827500D03*
X43100Y866100D03*
X37500Y912000D03*
Y907500D03*
X77000Y871500D03*
X62500Y862000D03*
X61500Y876500D03*
X78000Y878500D03*
X77500Y907000D03*
X85500Y903000D03*
X78300Y893900D03*
X77000Y863000D03*
X83400Y878600D03*
X47000Y877600D03*
X40900Y901500D03*
X76500Y900500D03*
X65900Y900000D03*
X64100Y904800D03*
X41000Y931899D03*
X86500Y932000D03*
X61500Y938500D03*
X81500Y940000D03*
X75500Y936500D03*
X69500Y939000D03*
X55500Y955500D03*
X56500Y940000D03*
X62500Y924500D03*
X70000Y914500D03*
Y925500D03*
X76500Y927000D03*
X85500Y915000D03*
X77500Y917000D03*
X64000Y980500D03*
X85500Y1009500D03*
X87000Y997500D03*
X55500Y968000D03*
X76400Y999100D03*
X37700Y991600D03*
X73000Y966000D03*
X66900Y969100D03*
X60000Y966800D03*
X81500Y985900D03*
X51500Y974100D03*
X87000Y1064000D03*
X39300Y1105800D03*
X83500Y1072000D03*
Y1067000D03*
Y1076500D03*
X37200Y1091700D03*
X67302Y1133490D03*
X78292Y1148041D03*
X64500Y1165700D03*
X52100Y1132700D03*
X79044Y1144112D03*
X66000Y1149500D03*
X37500Y1118900D03*
X74000Y1132000D03*
X40000Y1136000D03*
Y1156000D03*
X77293Y1129729D03*
X58000Y1206000D03*
X46000Y1218000D03*
X60000Y1194000D03*
X61000Y1173000D03*
X54000Y1184000D03*
X44000Y1194000D03*
X71000Y1232600D03*
X42000Y1242000D03*
X50000Y1244000D03*
X42000Y1266000D03*
X58000Y1250000D03*
Y1222000D03*
X39500Y1231000D03*
X51800Y1231600D03*
X50100Y1261500D03*
X42000Y1290000D03*
X50000Y1318000D03*
X40000Y1278000D03*
Y1298000D03*
X44000Y1306000D03*
X58000Y1312000D03*
Y1292000D03*
Y1272000D03*
X52000Y1296300D03*
X61000Y1363500D03*
X52500Y1368500D03*
X39000Y1333500D03*
X44000Y1326000D03*
Y1340000D03*
X54000Y1330000D03*
X72000Y1360000D03*
X83800Y1365900D03*
X84000Y1352000D03*
X81500Y1382000D03*
Y1416500D03*
Y1404000D03*
X71800Y1373900D03*
X83800Y1391900D03*
X70500Y1378500D03*
X69400Y1402900D03*
X39500Y1407900D03*
X55600Y1381700D03*
X48900Y1390500D03*
X60900D03*
X56700Y1400100D03*
X60600Y1423600D03*
X68800Y1417800D03*
X58800Y1412400D03*
X49000Y1413300D03*
X72900Y1393600D03*
X74900Y1408800D03*
X75600Y1420300D03*
X61500Y1380000D03*
X86900Y1451000D03*
X70400Y1444500D03*
X79000Y1436400D03*
X76200Y1430700D03*
X66500Y1433500D03*
X53100Y1430700D03*
X42600Y1444200D03*
X49100Y1448400D03*
X68500Y1454600D03*
X74500Y1461800D03*
X72300Y1469800D03*
X59000Y1444500D03*
X77000Y1449000D03*
X59000Y1472000D03*
X58100Y1459300D03*
X83500Y1469500D03*
X85200Y1515000D03*
X58500Y1519000D03*
X72000Y1514000D03*
X53500Y1519000D03*
X63000Y1482300D03*
X42700Y1500000D03*
X72700Y1480500D03*
X46500Y1484900D03*
X64100Y1495400D03*
X73000Y1491200D03*
X43300Y1518500D03*
X49500Y1505000D03*
X45400Y1523800D03*
X85000Y1490000D03*
X54500Y1574000D03*
X73900Y1535900D03*
X80000Y1531600D03*
X54300Y1541200D03*
X59500Y1541000D03*
X57500Y1562000D03*
X57000Y1568500D03*
X46600Y1541100D03*
X45300Y1563600D03*
X45900Y1532800D03*
X37900Y1570000D03*
X38800Y1541700D03*
X38300Y1561800D03*
X44400Y1592100D03*
X38300Y1579600D03*
X59500Y1627500D03*
X71600Y1607700D03*
X50600Y1589300D03*
Y1582800D03*
Y1595300D03*
Y1601300D03*
X55300Y1601100D03*
Y1595100D03*
Y1582600D03*
Y1589100D03*
X68700Y1603900D03*
X55400Y1613300D03*
X58500Y1607700D03*
X64400Y1605900D03*
X53300Y1609200D03*
X43200Y1634800D03*
X62300Y1641300D03*
X59500Y1667000D03*
X70000Y1668000D03*
X75500Y1679000D03*
X86000D03*
Y1669000D03*
X76000Y1646000D03*
X86000D03*
X76000Y1634000D03*
X86000D03*
Y1659500D03*
X75500D03*
X54000Y1646500D03*
X64500Y1646000D03*
X57500Y1634500D03*
X64000Y1634000D03*
X64500Y1658500D03*
X53500Y1659000D03*
X42500Y1699500D03*
X44600Y1724400D03*
X44900Y1706800D03*
X61500Y1716500D03*
X56000Y1695000D03*
Y1704500D03*
Y1712500D03*
X55500Y1723500D03*
X69000Y1684500D03*
X80500D03*
X62500Y1691500D03*
X65000Y1724000D03*
X62500Y1709000D03*
X72500Y1717000D03*
Y1699000D03*
X62500Y1700000D03*
X60000Y1730000D03*
X86500Y1713610D03*
Y1700110D03*
Y1726000D03*
X48400Y1746900D03*
X41600D03*
X38800Y1775000D03*
X53000Y1750500D03*
X36700Y1764700D03*
X56500Y1769300D03*
X44900Y1740300D03*
X64500Y1758500D03*
X55500Y1735500D03*
X65000Y1735000D03*
X79000Y1766500D03*
X65000Y1749000D03*
Y1768000D03*
Y1742500D03*
X71500Y1760000D03*
X72500Y1733000D03*
X87000Y1774110D03*
X42000Y1784400D03*
X81000Y1802000D03*
X73000Y1813000D03*
X64500Y1821500D03*
Y1812000D03*
Y1801500D03*
X65000Y1790000D03*
X72500Y1830000D03*
X72000Y1798000D03*
X86500Y1793110D03*
X57000Y1805500D03*
X39179Y1792306D03*
X39700Y1869700D03*
X46700Y1857700D03*
X46500Y1850200D03*
X44500Y1833500D03*
X46500Y1844000D03*
Y1865500D03*
X84000Y1869600D03*
X75500Y1838500D03*
X63500Y1863000D03*
Y1856000D03*
X64000Y1844500D03*
Y1834000D03*
X73000Y1847000D03*
X85100Y1844500D03*
X85700Y1852300D03*
X82000Y1915000D03*
X66000Y1917000D03*
X45100Y1933400D03*
X54500Y1889500D03*
X63500Y1928000D03*
X61500Y1922500D03*
X46000Y1923000D03*
X54000Y1928500D03*
X36500Y1900500D03*
X63500Y1963000D03*
X63594Y1935500D03*
X61600Y1954700D03*
X41100Y1957500D03*
X55300Y1959100D03*
X43500Y1945000D03*
X49053Y1951747D03*
X135000Y50000D03*
Y70000D03*
X128500Y89000D03*
X118000Y54500D03*
X124000Y74500D03*
X105000Y55000D03*
Y45000D03*
X95000D03*
X115000D03*
X125000D03*
X135000D03*
X137200Y123600D03*
X127700Y119200D03*
X128700Y104200D03*
X131000Y138100D03*
X118000Y124500D03*
X119000Y109500D03*
X118000Y142500D03*
X95000Y143000D03*
X105000D03*
X95000Y125000D03*
X105000D03*
X95000Y134000D03*
X129000Y160100D03*
X137900Y171400D03*
X131000Y150100D03*
X118000Y154500D03*
X95000Y155000D03*
X105000D03*
X131800Y289700D03*
X130900Y259100D03*
X114000Y296000D03*
X106000D03*
X96000D03*
X102000Y312000D03*
X104000Y304000D03*
X94000D03*
Y312000D03*
Y320000D03*
X111500Y390000D03*
X101300Y390100D03*
X105500Y390000D03*
X134000Y396000D03*
X118000D03*
Y386000D03*
X134000D03*
X105500Y406500D03*
X101500D03*
X107000Y426500D03*
X98000D03*
X102500D03*
X111200Y426400D03*
X110500Y406500D03*
X118500Y442000D03*
X122500Y450500D03*
X117000Y449000D03*
X89800Y446000D03*
X136000Y447000D03*
X131000D03*
X91900Y410500D03*
X88500Y426500D03*
X122500Y429000D03*
X125100Y408900D03*
X134000Y404500D03*
X118000Y424000D03*
Y404000D03*
X130000Y432000D03*
X134000Y414000D03*
X118000D03*
X134000Y424000D03*
X115000Y486100D03*
X129000Y485500D03*
X120000D03*
Y501500D03*
X110800Y482600D03*
X99800Y482000D03*
X110800Y488600D03*
X100000Y488000D03*
X110800Y500600D03*
X100000Y500000D03*
X129000Y501500D03*
X100000Y494000D03*
X110800Y494600D03*
X129000Y493500D03*
X120000D03*
X137000Y501500D03*
Y493000D03*
X136500Y485500D03*
X106500Y469500D03*
X115500Y476700D03*
X122500Y457500D03*
Y463500D03*
X121500Y475500D03*
X122500Y469500D03*
X117000Y455000D03*
Y460500D03*
Y466000D03*
Y471500D03*
X89800Y452900D03*
Y459000D03*
X111500Y473000D03*
X99500D03*
X89800Y464800D03*
X135500Y454000D03*
Y461000D03*
Y474500D03*
Y468000D03*
X130500Y454000D03*
Y461000D03*
Y468000D03*
Y474500D03*
X129000Y517500D03*
X100000Y512000D03*
X129000Y509500D03*
X110800Y512600D03*
X120000Y517500D03*
X100000Y506000D03*
X110800Y506600D03*
X120000Y509500D03*
Y523500D03*
X129000D03*
X137000Y510000D03*
X137500Y523500D03*
X100000Y519100D03*
X137500Y517500D03*
X117000Y530000D03*
X96900Y541600D03*
X99800Y545600D03*
X90630Y602020D03*
X120800Y598700D03*
X103100Y587600D03*
X87595Y581300D03*
X112018Y584900D03*
X106338Y580496D03*
X118565Y592846D03*
X94545Y601197D03*
X101800Y557400D03*
X135200Y566400D03*
X96500Y567600D03*
X112800Y653500D03*
X108200Y655825D03*
X99578Y605771D03*
X93063Y629134D03*
X91463Y623143D03*
X129000Y653600D03*
X88967Y659749D03*
X90674Y663367D03*
X121500Y683500D03*
X119576Y687008D03*
X120702Y690847D03*
X100600Y670600D03*
X122088Y665912D03*
X119300Y656600D03*
X111400Y658500D03*
X134100Y674500D03*
X119000Y673300D03*
X87310Y676796D03*
X124800Y696600D03*
X129800Y696800D03*
X98000Y674327D03*
X102913Y673973D03*
X107113Y674001D03*
X108500Y695500D03*
X103500D03*
X115000Y704500D03*
X99001Y694866D03*
X125202Y657500D03*
X105500Y732000D03*
X95500Y728000D03*
X125000Y734000D03*
X116500Y752000D03*
X125000Y751000D03*
X125500Y741500D03*
X130000Y736500D03*
X125000Y758500D03*
X120500Y732500D03*
X120000Y717500D03*
X117500Y724500D03*
X107000Y802400D03*
Y798200D03*
X106882Y794201D03*
X123000Y808500D03*
X114500Y805500D03*
X123000Y800000D03*
X122500Y792500D03*
X114000Y800000D03*
X113500Y792500D03*
X130000Y800000D03*
X129500Y792500D03*
X121500Y783500D03*
X121000Y776000D03*
X129500Y782000D03*
X129000Y774500D03*
X115200Y784200D03*
X115000Y773200D03*
X121000Y767900D03*
X109000Y809500D03*
X95500Y841500D03*
X124500Y858000D03*
X123500Y842500D03*
Y816000D03*
X115000Y813000D03*
X129200Y830400D03*
X129800Y813500D03*
X124500Y825100D03*
X134500Y840500D03*
X90500Y831500D03*
X119300Y837000D03*
X92700Y858100D03*
X92400Y848900D03*
X103400Y838300D03*
X137500Y903000D03*
X135500Y909000D03*
X124000D03*
X113500Y909500D03*
X103500D03*
X94000Y910500D03*
X116053Y903247D03*
X127000Y903000D03*
X90000Y893000D03*
X102500Y893500D03*
X117500Y893000D03*
X135000D03*
X134500Y885500D03*
X137500Y876500D03*
X125000Y868500D03*
X107000Y903000D03*
X124500Y876500D03*
X126000Y892500D03*
X96053Y903247D03*
X98700Y877100D03*
X92800Y865300D03*
X111100Y876700D03*
X108200Y953500D03*
X112984Y946835D03*
X120054Y945600D03*
X125500Y944000D03*
X105000Y958000D03*
X96500Y916500D03*
X107000Y918000D03*
X135000D03*
X135500Y927500D03*
X115000Y920000D03*
X125500D03*
X126000Y930000D03*
X115500D03*
X99000Y953000D03*
X88500Y940500D03*
X120000Y916000D03*
X126000Y954000D03*
X124618Y959244D03*
X110000Y949500D03*
X117529Y948844D03*
X93000Y925500D03*
X133500Y938000D03*
X130903Y958178D03*
X133500Y953000D03*
X94500Y950500D03*
X134000Y990500D03*
X125000Y967000D03*
X130500Y966000D03*
X124000Y971500D03*
X117000Y1008500D03*
X105500Y996000D03*
X95500Y999000D03*
X106500Y1008500D03*
X104000Y1014000D03*
X119000Y975000D03*
X136500Y967000D03*
X108500Y964000D03*
Y971000D03*
X114800Y1005000D03*
X135000Y975500D03*
X110400Y997850D03*
X119080Y992900D03*
X127700Y998400D03*
X87600Y965900D03*
X90542Y987958D03*
X97958Y966958D03*
X103500Y966500D03*
X130900Y1003400D03*
X91500Y1030500D03*
X91400Y1064100D03*
X95500Y1064000D03*
X97250Y1023500D03*
X110500Y1041500D03*
X111500Y1030000D03*
Y1020000D03*
X110500Y1064500D03*
Y1051000D03*
X103500Y1042000D03*
Y1028500D03*
X116500Y1049000D03*
Y1035500D03*
Y1062500D03*
X117500Y1023500D03*
X128500Y1076800D03*
X120000Y1108000D03*
Y1102000D03*
X115000Y1108500D03*
X110500Y1112000D03*
X103500Y1073500D03*
X104500Y1095000D03*
X116500Y1076000D03*
X109000Y1083500D03*
X89000Y1167400D03*
X101500Y1127500D03*
X106000D03*
X97000D03*
X97500Y1132500D03*
X118500Y1166000D03*
X105000Y1196000D03*
X119300Y1191400D03*
X119500Y1177500D03*
Y1205500D03*
X92000Y1214500D03*
X104500Y1208000D03*
X94000Y1189000D03*
X91500Y1200000D03*
X99000Y1265500D03*
X119000Y1269000D03*
X117500Y1251000D03*
X112000Y1250500D03*
Y1244500D03*
X119300Y1245400D03*
Y1219400D03*
X119500Y1231500D03*
X124000Y1270000D03*
X104500Y1219500D03*
X92000Y1254000D03*
X103500Y1229000D03*
X92000Y1241500D03*
X103000Y1244900D03*
X91500Y1229000D03*
X99500Y1310000D03*
Y1294000D03*
X98000Y1282000D03*
X123800Y1283900D03*
X113800Y1287900D03*
X114000Y1274000D03*
X123800Y1311900D03*
X124000Y1298000D03*
X114000Y1318000D03*
X92000Y1295500D03*
X91500Y1314500D03*
X114500Y1296500D03*
X97800Y1327900D03*
X123800Y1337900D03*
X124000Y1324000D03*
X113800Y1331900D03*
X115800Y1363900D03*
X116000Y1350000D03*
X123800Y1365900D03*
X124000Y1352000D03*
X114500Y1370500D03*
X93800Y1353900D03*
X94000Y1340000D03*
Y1366000D03*
X90800Y1331200D03*
X105500Y1415000D03*
X99600Y1416500D03*
X100500Y1384500D03*
Y1389000D03*
X124000Y1376500D03*
X114000Y1376000D03*
X93800Y1379900D03*
Y1393200D03*
X93600Y1407100D03*
X97500Y1412000D03*
X89700Y1409700D03*
X110000Y1418000D03*
X122862Y1385500D03*
X129000Y1416425D03*
X99500Y1407500D03*
X100000Y1443000D03*
X111833Y1469667D03*
X101000Y1460750D03*
X137000Y1429200D03*
X126600Y1461500D03*
X133500Y1467100D03*
X132200Y1424800D03*
X94000Y1427800D03*
X87200Y1431900D03*
X87700Y1446500D03*
X87300Y1436000D03*
X95500Y1468000D03*
X103700Y1470300D03*
X113024Y1452079D03*
X117122Y1448001D03*
X117195Y1456070D03*
X121338Y1452021D03*
X117024Y1452000D03*
X136100Y1463900D03*
X100200Y1433800D03*
X87200Y1440000D03*
X99800Y1455600D03*
X134400Y1454300D03*
X99700Y1450700D03*
X109500Y1438000D03*
X98500Y1428400D03*
X133000Y1447600D03*
X103000Y1429500D03*
X123000Y1431300D03*
X126975Y1435400D03*
X127300Y1468800D03*
X117000Y1435200D03*
X133799Y1440699D03*
X117500Y1519500D03*
X93000Y1518700D03*
X94000Y1514000D03*
X87900Y1523400D03*
X124500Y1524000D03*
X91300Y1488600D03*
X97000Y1503100D03*
X93500Y1482700D03*
X99170Y1485790D03*
X104333Y1498167D03*
X130180Y1486680D03*
X136500Y1481425D03*
X98000Y1564700D03*
X129000Y1555500D03*
X111500Y1537500D03*
X122000Y1558000D03*
X114000Y1552000D03*
X122000D03*
X114000Y1558000D03*
X122000Y1564000D03*
X121800Y1569929D03*
X114000Y1564000D03*
X122000Y1576000D03*
X102000Y1544000D03*
Y1562000D03*
Y1550000D03*
Y1556000D03*
Y1568000D03*
X94000D03*
X116000Y1576000D03*
X115900Y1569700D03*
X129000Y1535000D03*
X136000Y1568000D03*
X94000Y1556000D03*
X129000Y1549000D03*
X122000Y1538000D03*
X136000Y1542000D03*
X122000Y1546000D03*
X129000Y1542500D03*
X136000Y1536000D03*
X114000Y1546000D03*
X128000Y1568000D03*
X136000Y1562000D03*
Y1555000D03*
X129000Y1562500D03*
X136000Y1548000D03*
X119000Y1529500D03*
X94000Y1550000D03*
Y1562000D03*
X136000Y1528000D03*
X120500Y1606000D03*
X89500Y1610000D03*
X122000Y1584000D03*
X116000D03*
Y1592000D03*
X122000D03*
X116000Y1600000D03*
X122000Y1612000D03*
X104000Y1605500D03*
X116000Y1612000D03*
X122000Y1600000D03*
X128000Y1606000D03*
X94500Y1605500D03*
X113500D03*
X136500Y1651000D03*
X117500Y1679000D03*
X125000D03*
X107500D03*
X117500Y1669000D03*
X127500D03*
X97000D03*
X107000D03*
X127000Y1646000D03*
X138000Y1634000D03*
X137500Y1659500D03*
X118000Y1646000D03*
X138000D03*
X117000Y1633500D03*
X127500Y1633000D03*
Y1659500D03*
X117500D03*
X108000Y1646000D03*
X106000Y1634000D03*
X107000Y1659500D03*
X96000Y1646000D03*
X96500Y1634000D03*
X97000Y1659500D03*
X122000Y1685500D03*
X91000Y1685000D03*
X103000D03*
X112500D03*
X108500Y1727000D03*
X98500Y1717000D03*
Y1696500D03*
X99000Y1707000D03*
X97500Y1679500D03*
X109500Y1719500D03*
X110000Y1709500D03*
X109500Y1699000D03*
X119500Y1710110D03*
Y1696610D03*
Y1725110D03*
X111500Y1768500D03*
X117500Y1732000D03*
X119500Y1760000D03*
X97500Y1775500D03*
X108268Y1777300D03*
X119500Y1747110D03*
X138000Y1824000D03*
X110500Y1801000D03*
X88500Y1785000D03*
X97500Y1796000D03*
X98000Y1786000D03*
X107768Y1789110D03*
X120000Y1811500D03*
X119500Y1796500D03*
X137000Y1877500D03*
X114000Y1843500D03*
X97000Y1850500D03*
X99500Y1862500D03*
X106500D03*
X114500D03*
X122500D03*
X120500Y1836500D03*
Y1850500D03*
X108500Y1851610D03*
X116948Y1892000D03*
X124500Y1892403D03*
X132000Y1892000D03*
X118000Y1922000D03*
X184000Y55500D03*
X174000D03*
X164000D03*
X153000Y90500D03*
X154000Y75500D03*
X145000Y45000D03*
X155000D03*
X165000D03*
X175000D03*
X185000D03*
X180500Y112000D03*
X186000Y143000D03*
X187500Y130500D03*
X167000D03*
X176000Y131000D03*
X165500Y95500D03*
X174500Y143500D03*
X171500Y105500D03*
X170500Y120500D03*
X146500Y131859D03*
X154000Y105500D03*
X147600Y150900D03*
X165300Y145200D03*
X173500Y151500D03*
X185500D03*
X138800Y162100D03*
X141300Y298100D03*
X182000Y296000D03*
X172000D03*
X162000D03*
X142000Y291000D03*
X187500Y338000D03*
X180850Y348800D03*
X184500Y325500D03*
X143400Y318700D03*
X174000Y316000D03*
X164000D03*
X172000Y310000D03*
X182000D03*
X184000Y303000D03*
X176000Y302000D03*
X166000D03*
X143300Y343400D03*
X151300Y298200D03*
X188500Y364100D03*
X188300Y368600D03*
X181800Y369000D03*
X181100Y364050D03*
X150000Y386000D03*
Y396000D03*
X186600Y425750D03*
X162612Y438169D03*
X161600Y445900D03*
X161900Y451600D03*
X143400Y408200D03*
X174500Y432000D03*
X162000D03*
X145500Y427000D03*
X142000Y432000D03*
X150000Y404000D03*
Y414000D03*
Y424000D03*
X186500Y498000D03*
X144000Y501500D03*
X173600Y498800D03*
X169200Y482800D03*
X157100Y500000D03*
X144000Y493500D03*
Y486182D03*
X144400Y470800D03*
X162000Y457600D03*
X161900Y463300D03*
X188500Y474500D03*
X149000Y522500D03*
X186500Y513500D03*
X173700Y513900D03*
X144000Y517500D03*
X173500Y506000D03*
X186500D03*
Y519000D03*
X174900Y523300D03*
X156800Y515400D03*
Y506900D03*
X144600Y533800D03*
X147500Y551500D03*
X182600Y546900D03*
X174800Y532200D03*
X151500Y533000D03*
X164200Y541900D03*
X180500Y595000D03*
X171600Y595400D03*
X145500Y604000D03*
X141800Y559250D03*
X150500Y596000D03*
X153500Y574359D03*
X140700Y576600D03*
X149500Y574600D03*
X145230Y571700D03*
X163100Y604717D03*
X152700Y618803D03*
X170349Y619949D03*
X174100Y652900D03*
X167300Y653800D03*
X159700Y652000D03*
X175800Y617635D03*
X164950Y615700D03*
X180500Y627771D03*
X165600Y630269D03*
X176300Y608635D03*
X157200Y620800D03*
X146663Y634051D03*
X148595Y618300D03*
X151335Y640400D03*
X145200Y644600D03*
X153200Y653200D03*
X179017Y620013D03*
X151432Y661741D03*
X148995Y658568D03*
X185000Y673500D03*
X188100Y689100D03*
X176000Y679000D03*
Y665500D03*
X162300Y659100D03*
X183500Y698000D03*
X184700Y663900D03*
X165500Y677500D03*
X173000Y691000D03*
X142000Y701000D03*
X158500Y695000D03*
X145500Y675000D03*
X167600Y703300D03*
X184500Y708500D03*
X181000Y729000D03*
Y715500D03*
X182500Y758500D03*
Y745000D03*
X172000Y757500D03*
X181500Y738500D03*
X169100Y722100D03*
X145000Y711750D03*
X169000Y795500D03*
X163500Y805500D03*
X178000Y797500D03*
X187900Y785300D03*
X175000Y786500D03*
X173500Y777500D03*
Y764000D03*
X181700Y768400D03*
X165000Y786000D03*
X171500Y819500D03*
X177500Y812000D03*
Y826500D03*
X145500Y856500D03*
X140500Y846500D03*
X157500Y858000D03*
X185000Y843500D03*
X145500Y885000D03*
X143000Y910500D03*
X146000Y893000D03*
X184500Y879000D03*
Y865500D03*
X154700Y909700D03*
X156300Y877200D03*
X156500Y889000D03*
X187000Y891000D03*
X160500Y916500D03*
X153500Y941000D03*
X141000Y938500D03*
X144000Y919500D03*
Y929000D03*
X154500Y926500D03*
X185000Y917500D03*
X182000Y950500D03*
X139500Y951500D03*
X174000Y1012400D03*
X184000Y987500D03*
X143100Y1007100D03*
X146800Y1018900D03*
X143900Y1022700D03*
X162000Y1027000D03*
X166300Y1021300D03*
X182500Y1041500D03*
X183500Y1065500D03*
X182000Y1029500D03*
Y1016000D03*
X171000Y1046000D03*
Y1032500D03*
X175000Y1059000D03*
X160500Y1053500D03*
X181000Y1051000D03*
X164700Y1033600D03*
X176000Y1018500D03*
X171000Y1068000D03*
X166000Y1080000D03*
X173000Y1082000D03*
X165000Y1097000D03*
X181000Y1098500D03*
X175000Y1072500D03*
X160500Y1067000D03*
X187500Y1103500D03*
Y1090000D03*
X170000Y1103000D03*
Y1089500D03*
X157000Y1101500D03*
X159500Y1087500D03*
X181000Y1112500D03*
Y1079500D03*
X154600Y1111000D03*
X158500Y1075800D03*
X158595Y1110789D03*
X155000Y1130500D03*
Y1125000D03*
Y1120000D03*
X186000Y1133000D03*
X147500Y1165500D03*
X177102Y1129800D03*
X171502Y1129547D03*
X147500Y1186000D03*
X178644Y1202519D03*
X163344Y1181200D03*
X161500Y1227500D03*
X178500Y1268500D03*
X147500Y1221500D03*
X146500Y1241500D03*
X147000Y1265500D03*
X183500Y1241500D03*
X165000Y1264500D03*
X147500Y1288000D03*
Y1311000D03*
X164500Y1299500D03*
X147500Y1332000D03*
X147000Y1348000D03*
X147500Y1366500D03*
X147000Y1377000D03*
X146500Y1417619D03*
X159774Y1414374D03*
X148300Y1465000D03*
X173375Y1432500D03*
X149686Y1460007D03*
X152500Y1456000D03*
X165500Y1450600D03*
X138000Y1448500D03*
X174500Y1503500D03*
Y1509500D03*
X174000Y1515500D03*
Y1522000D03*
X142400Y1499900D03*
X148500Y1479500D03*
X148000Y1550000D03*
X170000Y1541000D03*
X148000Y1558000D03*
Y1528000D03*
Y1542000D03*
X168500Y1533500D03*
X170000Y1555000D03*
X161400Y1543500D03*
X150000Y1576000D03*
X156000Y1570000D03*
X154000Y1564000D03*
X170000Y1548500D03*
X169500Y1561500D03*
X161300Y1563100D03*
X148000Y1564000D03*
X156000Y1576000D03*
X168500Y1526000D03*
X166898Y1567102D03*
X150000Y1570000D03*
X156000Y1582000D03*
X156500Y1591000D03*
X150500Y1582000D03*
Y1591000D03*
X172000Y1606000D03*
X182500Y1599400D03*
X146000Y1612000D03*
X148000Y1606000D03*
X182500Y1592000D03*
X164000Y1606000D03*
X156500Y1600000D03*
X156000Y1606000D03*
X150500Y1600000D03*
X138500Y1606000D03*
X182500Y1584500D03*
X141500Y1673000D03*
X176000Y1646000D03*
X166000D03*
X158000D03*
X148000D03*
X176000Y1632000D03*
X178000Y1659500D03*
X167500Y1632500D03*
X170000Y1659500D03*
X149000Y1632500D03*
X159000D03*
Y1659500D03*
X148500Y1660000D03*
X139000Y1696500D03*
Y1712500D03*
X138500Y1727500D03*
X181500Y1716500D03*
X158500D03*
X167500Y1716000D03*
X182000Y1726000D03*
Y1704000D03*
X168500Y1705000D03*
X158500D03*
X184500Y1696500D03*
X163000Y1697000D03*
X174268Y1697110D03*
X152000D03*
Y1710610D03*
Y1725610D03*
X185000Y1738500D03*
X183600Y1765100D03*
X169000Y1781500D03*
X162500Y1773000D03*
X152500Y1771110D03*
X173268Y1776000D03*
X139000Y1800500D03*
X156500Y1782000D03*
X155500Y1798500D03*
X166500Y1798000D03*
X179000Y1798500D03*
X185500Y1804500D03*
X186000Y1790000D03*
X162000D03*
X172768Y1790110D03*
X152000D03*
X139000Y1851000D03*
X138500Y1839500D03*
X185000Y1852500D03*
X161500D03*
X183100Y1838300D03*
X160500Y1877500D03*
X173000Y1852610D03*
X151500Y1851110D03*
X139861Y1889461D03*
X161000Y1901500D03*
X194000Y55500D03*
X195000Y45000D03*
X200000Y55000D03*
Y65000D03*
Y75000D03*
Y85000D03*
X190500Y105000D03*
X189500Y120000D03*
X200000Y100000D03*
Y120000D03*
Y140000D03*
X191900Y167700D03*
X191700Y186500D03*
X201089Y181700D03*
X197500Y151500D03*
X191900Y244600D03*
X191800Y234900D03*
Y221100D03*
X191600Y206900D03*
X201500Y208000D03*
X201000Y222500D03*
X200500Y235000D03*
Y195900D03*
X202000Y295000D03*
Y274000D03*
Y254000D03*
X201089Y282600D03*
X202000Y264000D03*
Y340000D03*
Y328000D03*
X201089Y305500D03*
Y315500D03*
X201500Y397500D03*
Y378000D03*
X202000Y366500D03*
Y353000D03*
X192600Y392600D03*
X192471Y397355D03*
X201089Y388400D03*
X200500Y437500D03*
X201000Y430500D03*
X201089Y407000D03*
X200000Y420500D03*
X192400Y401900D03*
X192300Y410950D03*
X192409Y417655D03*
X190239Y447449D03*
X195600Y447500D03*
X189928Y435800D03*
X197500Y481500D03*
X192000Y490000D03*
Y498000D03*
X200300Y498100D03*
X199500Y489400D03*
X189900Y467500D03*
Y460500D03*
X190400Y453500D03*
X195000Y467500D03*
X194500Y474500D03*
X195000Y460500D03*
X195500Y453500D03*
X192000Y513500D03*
Y506000D03*
X190200Y523400D03*
X201089Y523500D03*
X193600Y519100D03*
X200100Y513600D03*
X199800Y506000D03*
X201200Y519200D03*
X201500Y544500D03*
X201089Y529500D03*
X201500Y552500D03*
X192400Y529400D03*
X191900Y538200D03*
X201500Y535000D03*
X192000Y543500D03*
X190500Y550500D03*
X202000Y578000D03*
Y586000D03*
Y595000D03*
X193700D03*
X194400Y586000D03*
X201089Y558000D03*
X201500Y564000D03*
X201089Y570600D03*
X202000Y607500D03*
X196500Y641500D03*
X192600Y633000D03*
X201500Y621500D03*
X202000Y650500D03*
X194000Y628500D03*
Y615000D03*
X192500Y645000D03*
X195000Y670000D03*
X197500Y685000D03*
X197000Y704000D03*
X202000Y676500D03*
X192500Y658500D03*
X191500Y692500D03*
X193100Y679000D03*
X196000Y718500D03*
X195500Y739000D03*
X197500Y753000D03*
X202000Y710000D03*
Y740500D03*
X191500Y724000D03*
Y710500D03*
Y746500D03*
X196000Y789500D03*
X196500Y797000D03*
X202000Y765000D03*
Y786000D03*
Y807500D03*
X191500Y760000D03*
X194500Y782500D03*
Y769000D03*
X196800Y828500D03*
X197000Y815000D03*
X190000Y823500D03*
X190500Y831000D03*
X201500Y835500D03*
X192500Y853000D03*
Y839500D03*
X192000Y879000D03*
Y865500D03*
X194000Y907000D03*
Y893500D03*
X192000Y934500D03*
Y921000D03*
Y962000D03*
Y948500D03*
X192500Y985500D03*
Y972000D03*
X195500Y1001000D03*
X190000Y1052000D03*
X195500Y1014500D03*
X193500Y1042500D03*
Y1029000D03*
X195000Y1061000D03*
Y1086500D03*
X194500Y1100500D03*
X195000Y1074500D03*
X201000Y1106500D03*
Y1093000D03*
X191800Y1280900D03*
X189000Y1432000D03*
X192500Y1543500D03*
Y1554000D03*
Y1533000D03*
Y1562500D03*
X196500Y1586000D03*
Y1595000D03*
X192500Y1617000D03*
Y1626500D03*
Y1634000D03*
Y1670500D03*
Y1664000D03*
X198500Y1713500D03*
X198000Y1691500D03*
X197500Y1776500D03*
X198000Y1754000D03*
Y1735500D03*
Y1818500D03*
X197500Y1800500D03*
X198500Y1859500D03*
X198000Y1838500D03*
X195000Y1874000D03*
X200000Y1882000D03*
X201500Y1900500D03*
X190500Y1924000D03*
X201000Y1923000D03*
X195500Y1905000D03*
G54D22*
X32800Y272300D03*
X29100Y321300D03*
X30100Y1083600D03*
X18600Y1644300D03*
X18400Y1720700D03*
X20200Y1692800D03*
X85800Y71500D03*
X56900Y155300D03*
Y163300D03*
Y179300D03*
Y159300D03*
Y175300D03*
X46500Y213400D03*
X57800Y217000D03*
X56900Y199300D03*
X70800Y431300D03*
X61000Y577200D03*
X78556Y690465D03*
X80700Y686400D03*
X83996Y848500D03*
Y844100D03*
Y852900D03*
X84000Y857200D03*
Y865700D03*
Y861500D03*
X45400Y916400D03*
X68700Y999800D03*
X84300Y1484000D03*
X49400Y1769800D03*
X88303Y61502D03*
X117900Y437500D03*
X125956Y692165D03*
X125856Y688065D03*
Y683665D03*
X112900Y670600D03*
X111900Y1408200D03*
X91300Y1451000D03*
X109700Y1425900D03*
X91300Y1439000D03*
X128800Y1482000D03*
X159900Y545600D03*
X162700Y622700D03*
X152329Y615065D03*
X171800Y701100D03*
X152096Y1419200D03*
Y1415000D03*
X140500Y1458400D03*
X152100Y1423400D03*
X190800Y439500D03*
G54D13*
X15906Y48110D03*
Y58110D03*
Y68110D03*
Y78110D03*
Y88110D03*
Y481339D03*
Y491339D03*
Y501339D03*
Y511339D03*
Y521339D03*
Y741181D03*
Y751181D03*
Y761181D03*
Y771181D03*
Y781181D03*
Y1187323D03*
Y1197323D03*
Y1207323D03*
Y1217323D03*
Y1227323D03*
Y1447165D03*
Y1457165D03*
Y1467165D03*
Y1477165D03*
Y1487165D03*
Y1880394D03*
Y1890394D03*
Y1900394D03*
Y1910394D03*
Y1920394D03*
X138937Y1778819D03*
X128937D03*
X118937D03*
X165000Y1370500D03*
Y1390500D03*
Y1380500D03*
G54D31*
X24100Y685300D03*
X28900D03*
X74100Y570600D03*
X82000Y702600D03*
X65635Y688306D03*
X70535D03*
X72200Y705400D03*
X67200D03*
X70800Y975800D03*
X64200Y998500D03*
X81398Y1132153D03*
X92300Y872854D03*
X87500D03*
X94000Y957200D03*
X103500Y974200D03*
X129900Y986900D03*
X140400Y566800D03*
X158535Y604079D03*
G54D40*
X83847Y61398D03*
X40000Y294300D03*
X56200Y252800D03*
X73500Y591000D03*
X76600Y986600D03*
X67600Y1025000D03*
X116900Y380100D03*
X91529Y533679D03*
X107100Y986000D03*
Y990800D03*
X94800Y1455500D03*
X106800Y1474500D03*
X165900Y532100D03*
X165700Y553300D03*
X182021Y613535D03*
X160300Y1462500D03*
G54D14*
X27559Y157480D03*
Y629921D03*
X17716Y1338583D03*
X27559Y1811023D03*
X179134Y78740D03*
X179133Y570866D03*
X179134Y1161417D03*
Y1889764D03*
G54D50*
X69000Y440000D03*
X74000D03*
X79000D03*
X84000D03*
X60400Y1575600D03*
X65400D03*
X70400D03*
X75400D03*
X96500Y439500D03*
X101500D03*
X106500D03*
X111500D03*
X128500Y1575500D03*
X133500D03*
X93500D03*
X98500D03*
X103500D03*
X108500D03*
X141000Y439500D03*
X146000D03*
X151000D03*
X156000D03*
X169000D03*
X174000D03*
X179000D03*
X184000D03*
X162500Y1575500D03*
X167500D03*
X172500D03*
X177500D03*
X138500D03*
X143500D03*
G54D23*
X27471Y262553D03*
X19721D03*
X23596Y255053D03*
X24925Y305350D03*
X32675D03*
X28800Y312850D03*
X35375Y1649050D03*
X27625D03*
X31500Y1641550D03*
X27292Y1714868D03*
X19542D03*
X23417Y1707368D03*
X58692Y909868D03*
X50942D03*
X54817Y902368D03*
X78752Y1613297D03*
Y1619703D03*
X131525Y722550D03*
X135400Y730050D03*
X137752Y1613297D03*
Y1619703D03*
X109252Y1613297D03*
Y1619703D03*
X141625Y682250D03*
X149375D03*
X145500Y689750D03*
X139275Y722550D03*
X138694Y1422269D03*
X146444D03*
X148025Y1401454D03*
X155775D03*
X151900Y1408954D03*
X165494Y1437469D03*
X173244D03*
X169369Y1444969D03*
X142569Y1429769D03*
X165252Y1613297D03*
Y1619703D03*
G54D32*
X31868Y1089208D03*
Y1096958D03*
X24368Y1093083D03*
X112018Y566991D03*
Y574741D03*
X104518Y570866D03*
X112018Y1255968D03*
Y1263718D03*
X104518Y1259843D03*
G54D41*
X67998Y56503D03*
X67398Y71003D03*
X60600Y195000D03*
X61000Y240000D03*
X61600Y211300D03*
X54300Y263300D03*
X58300D03*
X37200Y256900D03*
X62600Y249200D03*
X73700Y543300D03*
X78600Y574500D03*
X73900Y558800D03*
X39000Y581300D03*
X77200Y705900D03*
X77000Y730800D03*
X43400Y896100D03*
X81398Y1126103D03*
X63498Y1123803D03*
X63198Y1142003D03*
X48300Y1755700D03*
X136779Y543071D03*
X116800Y588596D03*
X128900D03*
X91300Y573200D03*
X136679Y557171D03*
X129335Y662029D03*
X133535D03*
X104900Y662200D03*
X115600Y660200D03*
X116300Y670600D03*
X119600Y831800D03*
X111200D03*
X102900Y831796D03*
X121671Y939756D03*
X117300Y939700D03*
X110500D03*
X136000Y947800D03*
X131500D03*
X123300Y1001300D03*
X119300D03*
X114800D03*
X99000Y979700D03*
X135000Y1003200D03*
X123000Y1424200D03*
X127500D03*
X95500Y1464200D03*
X118000Y1424200D03*
X95600Y1423700D03*
X137000Y1501700D03*
X133000D03*
X129000D03*
X125000D03*
X121000D03*
X117000D03*
X113000D03*
X109000D03*
X93500Y1479200D03*
X145300Y582200D03*
X153500Y570000D03*
X151335Y635829D03*
X148435Y653329D03*
X144235D03*
X154500Y702700D03*
X167700Y699600D03*
X158500Y702700D03*
X149000Y949200D03*
X153000D03*
X157000D03*
X145000D03*
X140500Y947800D03*
X139100Y1003100D03*
X156631Y1431081D03*
X160831Y1430281D03*
X152331Y1431081D03*
X148500Y1474100D03*
X165400Y1430200D03*
X151000Y1491200D03*
X146500D03*
X142000D03*
X137900Y1491100D03*
G54D24*
X32500Y321300D03*
X33500Y1083600D03*
X22000Y1644300D03*
X21800Y1720700D03*
X23600Y1692800D03*
X60300Y155300D03*
Y163300D03*
Y179300D03*
Y159300D03*
Y175300D03*
X49900Y213400D03*
X61200Y217000D03*
X60300Y199300D03*
X36200Y272300D03*
X74200Y431300D03*
X64400Y577200D03*
X81956Y690465D03*
X84100Y686400D03*
X48800Y916400D03*
X72100Y999800D03*
X52800Y1769800D03*
X91703Y61502D03*
X89200Y71500D03*
X121300Y437500D03*
X129356Y692165D03*
X129256Y688065D03*
Y683665D03*
X116300Y670600D03*
X87396Y848500D03*
Y844100D03*
Y852900D03*
X87400Y857200D03*
Y865700D03*
Y861500D03*
X115300Y1408200D03*
X94700Y1451000D03*
X113100Y1425900D03*
X94700Y1439000D03*
X87700Y1484000D03*
X132200Y1482000D03*
X163300Y545600D03*
X166100Y622700D03*
X155729Y615065D03*
X175200Y701100D03*
X155496Y1419200D03*
Y1415000D03*
X143900Y1458400D03*
X155500Y1423400D03*
X194200Y439500D03*
G54D51*
X76500Y454565D03*
X67900Y1590165D03*
X104000Y454065D03*
X136000Y1590065D03*
X101000D03*
X148500Y454065D03*
X176500D03*
X170000Y1590065D03*
G54D60*
X77400Y980050D03*
Y976300D03*
Y972550D03*
X88000D03*
Y976300D03*
Y980050D03*
G54D42*
X67998Y53103D03*
X67398Y67603D03*
X60600Y191600D03*
X62600Y245800D03*
X61000Y236600D03*
X61600Y207900D03*
X54300Y259900D03*
X58300D03*
X37200Y253500D03*
X73700Y539900D03*
X78600Y571100D03*
X73900Y555400D03*
X39000Y577900D03*
X77200Y702500D03*
X77000Y727400D03*
X43400Y892700D03*
X81398Y1122703D03*
X63498Y1120403D03*
X63198Y1138603D03*
X48300Y1752300D03*
X136779Y539671D03*
X116800Y585196D03*
X128900D03*
X91300Y569800D03*
X136679Y553771D03*
X129335Y658629D03*
X133535D03*
X104900Y658800D03*
X115600Y656800D03*
X116300Y667200D03*
X119600Y828400D03*
X111200D03*
X102900Y828396D03*
X121671Y936356D03*
X117300Y936300D03*
X110500D03*
X136000Y944400D03*
X131500D03*
X123300Y997900D03*
X119300D03*
X114800D03*
X99000Y976300D03*
X135000Y999800D03*
X123000Y1420800D03*
X127500D03*
X118000D03*
X95600Y1420300D03*
X95500Y1460800D03*
X137000Y1498300D03*
X133000D03*
X129000D03*
X125000D03*
X121000D03*
X117000D03*
X113000D03*
X109000D03*
X93500Y1475800D03*
X145300Y578800D03*
X153500Y566600D03*
X151335Y632429D03*
X148435Y649929D03*
X144235D03*
X154500Y699300D03*
X167700Y696200D03*
X158500Y699300D03*
X149000Y945800D03*
X153000D03*
X157000D03*
X145000D03*
X140500Y944400D03*
X139100Y999700D03*
X156631Y1427681D03*
X160831Y1426881D03*
X152331Y1427681D03*
X148500Y1470700D03*
X165400Y1426800D03*
X151000Y1487800D03*
X146500D03*
X142000D03*
X137900Y1487700D03*
G54D15*
X32425Y177900D03*
X26450Y274750D03*
X34200Y284800D03*
X32600Y290500D03*
X25500Y321200D03*
X21600Y333800D03*
X29500Y343500D03*
X23100Y342400D03*
X32675Y299500D03*
X23400Y353500D03*
X34000Y448000D03*
X29500Y410500D03*
X33200Y468900D03*
X14000Y476000D03*
X28800Y533700D03*
X5304Y548800D03*
Y528900D03*
X33450Y574300D03*
X5094Y574500D03*
X29500Y586500D03*
X23450Y577491D03*
X25148Y570800D03*
X27000Y573800D03*
X4594Y749000D03*
Y714000D03*
X5000Y1355000D03*
X26700Y1529800D03*
X28000Y1596800D03*
X13300Y1644300D03*
X10500Y1648800D03*
X35500Y1670500D03*
X31400Y1648200D03*
X13300Y1689600D03*
X19542Y1710518D03*
X29100Y1721550D03*
X34000Y1691500D03*
X19200Y1707000D03*
X25000Y1763800D03*
X22000Y1787800D03*
X27400Y1899400D03*
X64000Y67553D03*
X64500Y53000D03*
X70454Y60031D03*
X74000Y60500D03*
X79000Y65500D03*
X75000Y67500D03*
X84500Y56500D03*
X81500Y75500D03*
X63500Y63500D03*
X59600Y125800D03*
X75300Y155300D03*
X49924Y153261D03*
X53000Y171500D03*
X65000Y166300D03*
X60350Y151950D03*
X39300Y181100D03*
X63500Y179300D03*
X53400Y191300D03*
X39300Y175500D03*
X43700Y181200D03*
X43400Y174325D03*
X52700Y162300D03*
X64400Y183400D03*
X52500Y175200D03*
X70500Y190200D03*
X54400Y217000D03*
X65200Y207850D03*
X57424Y232974D03*
X42720Y233990D03*
X65000Y241500D03*
Y235400D03*
X54200Y207850D03*
Y220700D03*
X51700Y234800D03*
X41100Y231000D03*
X71400Y208150D03*
X69900Y236600D03*
X77900Y229034D03*
X70600Y217600D03*
X74800Y231800D03*
X69400Y226100D03*
X61300Y229400D03*
X38000Y228500D03*
X75300Y211300D03*
X85676Y231100D03*
X72100Y221700D03*
X49700Y209700D03*
X53500Y199700D03*
X47800Y199200D03*
X64000Y199700D03*
X60300Y275700D03*
X57500Y268500D03*
X68000Y268000D03*
X70600Y250500D03*
X42500Y254100D03*
X48500Y248600D03*
X42500Y260200D03*
X36000Y260386D03*
X58936Y256289D03*
X52500Y248500D03*
X50800Y266400D03*
X54000Y275600D03*
X45800Y277800D03*
X43400Y272300D03*
X78000Y429500D03*
X52100Y513100D03*
X46500Y511000D03*
X46000Y516000D03*
X51000Y529500D03*
X66000Y550500D03*
X71445Y532192D03*
X72397Y528297D03*
X77800Y540300D03*
X63400Y581400D03*
X49700Y568900D03*
X65000Y561500D03*
X78400Y583700D03*
X70350Y558850D03*
X54600Y573400D03*
X82000Y652000D03*
X66200Y653500D03*
X84200Y643865D03*
X75571Y692496D03*
X53000Y673500D03*
X57684Y697639D03*
X64000Y666600D03*
X52500Y682500D03*
X78494Y697835D03*
X53000Y695100D03*
X39800Y681400D03*
X86597Y681103D03*
X43388Y694286D03*
X49500Y703500D03*
X46500Y705500D03*
X44500Y697500D03*
X60900Y670200D03*
X60500Y682540D03*
X76100Y686900D03*
X83850Y678109D03*
X73000Y728000D03*
X69000Y726800D03*
X71500Y735500D03*
X73500Y732000D03*
X86500Y723500D03*
X57500Y844500D03*
X72400Y822900D03*
X51200Y827000D03*
X61207Y828350D03*
X49600Y889400D03*
X55700Y880000D03*
X59500Y881600D03*
X57500Y890300D03*
X56000Y885500D03*
X64600Y882700D03*
X61600Y885200D03*
X67200Y888800D03*
X54300Y915500D03*
X54000Y996500D03*
X70800Y990500D03*
X57500Y987800D03*
Y984300D03*
X83500Y976300D03*
Y972800D03*
X83000Y979800D03*
X53800Y1006200D03*
X53500Y1025500D03*
X56000Y1021500D03*
X54500Y1035500D03*
X51000Y1018000D03*
X82094Y1112500D03*
X64500Y1099000D03*
X37500Y1099823D03*
X70500Y1161500D03*
X73163Y1158780D03*
X71100Y1171000D03*
X68800Y1178800D03*
X39400Y1381300D03*
X44500Y1380500D03*
X45500Y1400000D03*
X80000Y1472000D03*
X83200Y1455500D03*
X45000Y1428000D03*
X36400Y1523400D03*
X67700Y1568700D03*
X43500Y1620700D03*
X42700Y1606000D03*
X38400Y1596700D03*
X83000Y1619703D03*
X83050Y1616000D03*
X42500Y1673000D03*
X44500Y1678000D03*
X43600Y1668300D03*
X43300Y1646600D03*
X45500Y1690000D03*
X41500Y1692000D03*
X40300Y1703900D03*
X44100Y1685200D03*
X45300Y1776300D03*
X52500Y1756000D03*
X55900Y1881500D03*
X62000Y1877000D03*
X57900Y1899800D03*
X65300Y1886600D03*
X38700Y1893800D03*
X41500Y1889500D03*
X60300Y1892300D03*
X47000Y1886200D03*
X79900Y1923000D03*
X109500Y62000D03*
X89500Y49500D03*
X99500Y61000D03*
X115000Y76500D03*
X109000D03*
X98500Y73000D03*
X115500Y59500D03*
X97000Y51500D03*
X91500Y88500D03*
Y92500D03*
X92500Y73000D03*
X88253Y65500D03*
X112000Y101000D03*
X104500D03*
X91000Y97000D03*
X93000Y107000D03*
X93900Y111800D03*
X93500Y101500D03*
X117600Y234900D03*
X122100Y230100D03*
X127200Y246000D03*
X122500Y441000D03*
X135500D03*
X108100Y477650D03*
X91300Y528200D03*
X108900Y541300D03*
X102700Y541000D03*
X106300Y553200D03*
X110400Y550800D03*
X87700Y528000D03*
X132500Y539621D03*
X115300Y551800D03*
X129000Y597000D03*
X124200Y568400D03*
X119800Y568300D03*
X133500Y575500D03*
X137000Y589900D03*
X133500Y582000D03*
X134600Y586700D03*
X88000Y586500D03*
X101000Y583000D03*
X96000Y588000D03*
X89000Y595000D03*
X87000Y591000D03*
X135000Y561500D03*
X121000Y581500D03*
X124900Y582000D03*
X91300Y577000D03*
X92200Y553800D03*
X116000Y596900D03*
X113655Y599363D03*
X128900Y580500D03*
X122300Y575000D03*
X131135Y639554D03*
X87000Y648000D03*
X122500Y653650D03*
X117400Y653100D03*
X91250Y704700D03*
X134600Y665600D03*
X130000Y700500D03*
X122500D03*
X114500D03*
X105500Y702500D03*
X93000Y698500D03*
X88500Y700000D03*
X98000Y698500D03*
Y703000D03*
X100200Y663900D03*
X118127Y663400D03*
X109005Y665890D03*
X114000Y663350D03*
X130000Y753000D03*
Y746000D03*
X119500Y757500D03*
Y746500D03*
Y739500D03*
X113500Y729000D03*
Y736000D03*
Y747000D03*
Y756000D03*
Y721000D03*
X106000Y709000D03*
X98000Y708000D03*
X130000Y764000D03*
X118700Y840700D03*
X98900Y822900D03*
X114900Y824100D03*
X106404Y840700D03*
X100300Y841000D03*
X111500Y851600D03*
X101500Y874200D03*
X102300Y863438D03*
X107164Y862285D03*
X113400Y862200D03*
X125400Y983600D03*
Y992000D03*
X97300Y990800D03*
X94000Y971800D03*
X104000Y1062500D03*
Y1049500D03*
X127200Y1015200D03*
X105000Y1181000D03*
X119500Y1261000D03*
X119000Y1255968D03*
X128700Y1408000D03*
X135601Y1416200D03*
X134500Y1420000D03*
X125000Y1398500D03*
X100860Y1402260D03*
X111000Y1394000D03*
X125100Y1402500D03*
X131174Y1412700D03*
X89000Y1428171D03*
X110000Y1429500D03*
X132000Y1436500D03*
X112750Y1491250D03*
X121000Y1506500D03*
X113000D03*
X117000D03*
X109000D03*
X133000Y1505500D03*
X128999Y1506499D03*
X125000Y1506500D03*
X135008Y1508245D03*
X132300Y1491100D03*
X108500Y1569000D03*
X113200Y1622800D03*
Y1619300D03*
X91100Y1922800D03*
X128900Y1923300D03*
X104600Y1923400D03*
X133500Y1906500D03*
X149500Y52000D03*
X146960Y432400D03*
X142000Y478500D03*
X165300Y481100D03*
X144000Y509500D03*
X166100Y527900D03*
X147000Y529900D03*
X156300Y552100D03*
X142500Y550000D03*
X162500Y527900D03*
X159850Y541800D03*
X182588Y542288D03*
X154600Y581500D03*
X159250Y590250D03*
X145800Y594400D03*
X142100Y581400D03*
X160000Y562500D03*
X147900Y588100D03*
X138900Y650100D03*
X139200Y653900D03*
X174196Y628196D03*
X150978Y687775D03*
X142648Y665429D03*
X165433Y692372D03*
X161000Y674000D03*
X157500Y664500D03*
X147000Y703000D03*
X149000Y677000D03*
X155200Y679500D03*
X161500Y691700D03*
X150700D03*
X153192Y705890D03*
X146000Y755000D03*
X166000Y751500D03*
X170000Y745500D03*
X161600Y739800D03*
X161500Y747500D03*
X146000Y726000D03*
X165900Y717300D03*
X146000Y738000D03*
X175100Y710000D03*
X158600Y752600D03*
X146000Y765500D03*
Y796500D03*
Y782500D03*
X166000Y760000D03*
X166500Y775500D03*
X161500Y759000D03*
Y768000D03*
Y778000D03*
X146500Y812000D03*
X146000Y824000D03*
X180000Y856000D03*
X162000Y817500D03*
X174000Y834500D03*
X168000Y830000D03*
X180000Y872500D03*
X179500Y884000D03*
X179900Y900900D03*
X157800Y898000D03*
X147500Y900500D03*
X180000Y960400D03*
X179900Y925700D03*
X179800Y941400D03*
X180000Y912500D03*
X143000Y953032D03*
X146500Y953030D03*
X149772Y954121D03*
X152747Y952474D03*
X163100Y978600D03*
X163200Y985200D03*
X149800Y1008700D03*
X179000Y1005000D03*
X180500Y973200D03*
X150500Y976500D03*
X155000Y974500D03*
X155500Y1030000D03*
X153500Y1033500D03*
X151500Y1030500D03*
X159500Y1062000D03*
X163000Y1042500D03*
X146500Y1397100D03*
X155900D03*
X139900Y1415100D03*
X142500Y1420500D03*
X169000Y1426750D03*
X158500Y1466500D03*
X151500Y1438500D03*
X157500Y1454800D03*
X142000Y1494800D03*
X147500Y1498000D03*
X153500Y1496500D03*
X143518Y1567520D03*
X177500Y1569500D03*
X141300Y1625000D03*
X169876Y1626303D03*
X141500Y1621600D03*
X173270Y1626517D03*
X152500Y1883100D03*
X184500Y1920500D03*
X170000D03*
X162100Y1912000D03*
X151900Y1891400D03*
X146300Y1913700D03*
X142400Y1923800D03*
X176700Y1923900D03*
X177700Y1912800D03*
X157900Y1923100D03*
X201500Y165000D03*
X191400Y432405D03*
X202210Y638500D03*
X201500Y691500D03*
X202500Y666000D03*
X201500Y726500D03*
X202500Y755500D03*
X201500Y777000D03*
X201389Y797000D03*
X202000Y859500D03*
X202500Y822000D03*
Y846500D03*
X202000Y890000D03*
X202210Y903500D03*
X202000Y875000D03*
X202500Y945500D03*
X202000Y918000D03*
X202500Y962000D03*
X201500Y931500D03*
X202500Y1006000D03*
Y977500D03*
X201500Y991000D03*
X202000Y1037000D03*
Y1052000D03*
X201500Y1019000D03*
X201389Y1067000D03*
X201500Y1082500D03*
X195000Y1112000D03*
X201500Y1147000D03*
X202000Y1212000D03*
X202500Y1179000D03*
X202000Y1246000D03*
X201500Y1306500D03*
X202500Y1280000D03*
X201500Y1359500D03*
Y1350000D03*
X201700Y1388300D03*
X201500Y1413000D03*
X202400Y1444000D03*
X201389Y1425500D03*
X202210Y1462000D03*
X194500Y1510000D03*
Y1505500D03*
X196500Y1572000D03*
Y1606500D03*
X192500Y1653000D03*
Y1648000D03*
X192650Y1641500D03*
X200500Y1876500D03*
X201200Y1890500D03*
X201100Y1908800D03*
G54D33*
X32359Y1680500D03*
X60641D03*
G54D61*
X57100Y974900D03*
G54D70*
X96457Y1747835D03*
Y1823031D03*
X178937Y1328740D03*
X161417Y1747835D03*
Y1823031D03*
G54D25*
X22900Y397800D03*
Y418300D03*
X19100Y667000D03*
X36600Y1551500D03*
X81100Y398500D03*
X47700Y397800D03*
X81100Y419000D03*
X47700Y418300D03*
X43900Y667000D03*
X73600Y798400D03*
X63700Y1090600D03*
X88500D03*
X61400Y1551500D03*
X137900Y88500D03*
X113100D03*
X105900Y398500D03*
Y419000D03*
X98400Y798400D03*
X185300Y397900D03*
X160500D03*
X185200Y356700D03*
X160400D03*
X185400Y376900D03*
X160600D03*
X185300Y418400D03*
X160500D03*
X184900Y1531500D03*
X160100D03*
X185000Y1551600D03*
X160200D03*
G54D34*
X21350Y1781000D03*
X34650D03*
X77953Y54502D03*
X71650Y584000D03*
X58350D03*
X45050Y593000D03*
X58350D03*
X81850Y715400D03*
X81350Y740400D03*
X60150Y1011800D03*
X73450D03*
X64450Y1032100D03*
X77750D03*
X91253Y54502D03*
X95850Y68500D03*
X109150D03*
X95150Y715400D03*
X94650Y740400D03*
G54D52*
X72000Y473548D03*
Y491452D03*
X90000Y473548D03*
Y491452D03*
X176000Y473048D03*
Y490952D03*
X158000Y473048D03*
Y490952D03*
G54D43*
X71802Y56547D03*
X71400Y71754D03*
X75200Y741500D03*
X75700Y719100D03*
X53800Y1013100D03*
X103500Y597500D03*
X146365Y611321D03*
G54D16*
X31299Y230866D03*
Y220866D03*
Y210866D03*
Y348563D03*
Y338563D03*
Y358563D03*
Y903917D03*
Y923917D03*
Y913917D03*
Y1064587D03*
Y1054587D03*
Y1044587D03*
Y1619941D03*
Y1609941D03*
Y1629941D03*
Y1757638D03*
Y1747638D03*
Y1737638D03*
G54D17*
X27900Y246900D03*
X25300Y328500D03*
X36300D03*
X16200Y1657100D03*
X27200D03*
X15800Y1699200D03*
X26800D03*
X38900Y246900D03*
X124696Y1392300D03*
X135696D03*
X106000Y1387500D03*
X117000D03*
X154000D03*
X143000D03*
G54D62*
X57100Y979300D03*
G54D53*
X85400Y544750D03*
X83430D03*
X81465D03*
Y561050D03*
X83430D03*
X85400D03*
X89335Y544750D03*
X87370D03*
Y561050D03*
X89335D03*
X108710Y612629D03*
X110675D03*
X112645D03*
X114615D03*
X116580D03*
X118550D03*
X120520D03*
X122490D03*
X124455D03*
X126425D03*
X128395D03*
X130360D03*
Y646029D03*
X128395D03*
X126425D03*
X124455D03*
X122490D03*
X120520D03*
X118550D03*
X116580D03*
X114615D03*
X112645D03*
X110675D03*
X108710D03*
X153135Y542950D03*
X151170D03*
X149200D03*
X147230D03*
X145265D03*
Y559250D03*
X147230D03*
X149200D03*
X151170D03*
X153135D03*
G54D71*
X136235Y618504D03*
Y620469D03*
Y622439D03*
Y624409D03*
Y626374D03*
Y628344D03*
Y630314D03*
Y632284D03*
Y634249D03*
Y636219D03*
Y638189D03*
Y640154D03*
X102835D03*
Y638189D03*
Y636219D03*
Y634249D03*
Y632284D03*
Y630314D03*
Y628344D03*
Y626374D03*
Y624409D03*
Y622439D03*
Y620469D03*
Y618504D03*
G54D26*
X33400Y570800D03*
X27700Y1106000D03*
X22000Y1640200D03*
X34100Y1774400D03*
X23300Y1769600D03*
X70700Y63500D03*
X60300Y171300D03*
Y183300D03*
Y167300D03*
Y187300D03*
X61200Y221000D03*
X49900Y217400D03*
X36082Y264217D03*
X60300Y280000D03*
X81944Y694635D03*
X83400Y682200D03*
X68700Y730000D03*
X72100Y1004300D03*
X63000Y1020600D03*
X75700Y1025400D03*
X75800Y1020900D03*
X41400Y1096000D03*
X72200Y1175100D03*
X38400Y1788200D03*
X102100Y549600D03*
X87100Y569900D03*
X94700Y671000D03*
X119000Y660200D03*
X108300Y662200D03*
X91200Y707900D03*
X89700Y733400D03*
X113100Y1421600D03*
X107500Y1408100D03*
X133200Y1428300D03*
X94700Y1446500D03*
X153500Y430800D03*
X148700Y568000D03*
X156200Y587000D03*
X166100Y626700D03*
X177700Y624300D03*
X151404Y1394000D03*
X143900Y1466400D03*
Y1462400D03*
X143600Y1453300D03*
X160700Y1458000D03*
G54D35*
X33600Y1769900D03*
X81300Y71500D03*
X63800Y662300D03*
Y657600D03*
X54300Y1764700D03*
X115800Y769100D03*
Y764100D03*
X105300Y1058400D03*
Y1053700D03*
X187900Y1652700D03*
Y1648000D03*
X147447Y1878698D03*
X147400Y1883700D03*
G54D44*
X71802Y52947D03*
X71400Y68154D03*
X75200Y737900D03*
X75700Y715500D03*
X53800Y1009500D03*
X103500Y593900D03*
X146365Y607721D03*
G54D80*
X125000Y1409454D03*
X121125Y1401954D03*
X128875D03*
G54D27*
X35000Y581300D03*
X58100Y1030800D03*
X87400Y574100D03*
X149500Y578600D03*
X164600Y608500D03*
X150500Y699200D03*
G54D18*
X34400Y294300D03*
X78247Y61398D03*
X50600Y252800D03*
X85929Y533679D03*
X67900Y591000D03*
X71000Y986600D03*
X62000Y1025000D03*
X111300Y380100D03*
X101500Y986000D03*
Y990800D03*
X89200Y1455500D03*
X101200Y1474500D03*
X160300Y532100D03*
X160100Y553300D03*
X176421Y613535D03*
X154700Y1462500D03*
G54D90*
X147500Y1437250D03*
X143625Y1444750D03*
X151375D03*
G54D45*
X85550Y103000D03*
X77650D03*
X82250Y776700D03*
X75950Y1069700D03*
X68050D03*
X90150Y776700D03*
G54D72*
X89435Y642629D03*
Y635029D03*
X89500Y1461700D03*
Y1469300D03*
X172100Y549100D03*
Y541500D03*
X152265Y601371D03*
X170100Y607600D03*
Y615200D03*
X152265Y608971D03*
X167000Y1457700D03*
Y1465300D03*
G54D63*
X70202Y1138347D03*
Y1125047D03*
X41600Y1767550D03*
Y1754250D03*
X88502Y1136247D03*
Y1122947D03*
G54D81*
X111882Y1461600D03*
X114441D03*
X117000D03*
X119559D03*
X122118D03*
Y1442400D03*
X119559D03*
X117000D03*
X114441D03*
X111882D03*
G54D36*
X28000Y1769900D03*
X75700Y71500D03*
X58200Y662300D03*
Y657600D03*
X48700Y1764700D03*
X110200Y769100D03*
Y764100D03*
X99700Y1058400D03*
Y1053700D03*
X182300Y1652700D03*
Y1648000D03*
X141847Y1878698D03*
X141800Y1883700D03*
G54D54*
X73900Y550100D03*
X136771Y548521D03*
X132735Y593429D03*
X125835Y593629D03*
X131935Y601929D03*
X105000Y603200D03*
X101900Y654100D03*
X92971Y617335D03*
X117100Y1430100D03*
X144329Y598765D03*
X139929Y604165D03*
X140135Y593229D03*
X160700Y615900D03*
X151029Y627565D03*
X156700Y626800D03*
X179000Y706500D03*
X147600Y994600D03*
X154000Y994500D03*
X142000D03*
G54D37*
X30300Y1787800D03*
X64500Y573000D03*
X81900Y966200D03*
X71200Y1144500D03*
X87000Y1143000D03*
X94800Y1431500D03*
Y1434900D03*
X133300Y1432000D03*
X94800Y1442800D03*
X163400Y549300D03*
X144300Y695500D03*
G54D28*
X35000Y584900D03*
X58100Y1034400D03*
X87400Y577700D03*
X149500Y582200D03*
X164600Y612100D03*
X150500Y702800D03*
G54D64*
X80200Y1477500D03*
X107600Y558300D03*
X115200D03*
X87800Y1477500D03*
X106770Y1480640D03*
X99170D03*
X183700Y1606500D03*
X180700Y1641000D03*
X188300D03*
X191300Y1606500D03*
G54D73*
X93206Y677415D03*
Y682415D03*
Y687415D03*
Y692415D03*
X113306D03*
Y687415D03*
Y682415D03*
Y677415D03*
G54D82*
X126600Y1457118D03*
Y1454559D03*
Y1452000D03*
Y1449441D03*
Y1446882D03*
X107400D03*
Y1449441D03*
Y1452000D03*
Y1454559D03*
Y1457118D03*
G54D91*
X142300Y1471800D03*
Y1480800D03*
G54D19*
X32682Y264217D03*
X30000Y570800D03*
X24300Y1106000D03*
X18600Y1640200D03*
X30700Y1774400D03*
X19900Y1769600D03*
X35000Y1788200D03*
X67300Y63500D03*
X56900Y171300D03*
Y183300D03*
Y167300D03*
Y187300D03*
X57800Y221000D03*
X46500Y217400D03*
X56900Y280000D03*
X83700Y569900D03*
X78544Y694635D03*
X80000Y682200D03*
X86300Y733400D03*
X65300Y730000D03*
X68700Y1004300D03*
X59600Y1020600D03*
X72300Y1025400D03*
X72400Y1020900D03*
X38000Y1096000D03*
X68800Y1175100D03*
X98700Y549600D03*
X91300Y671000D03*
X115600Y660200D03*
X104900Y662200D03*
X87800Y707900D03*
X109700Y1421600D03*
X104100Y1408100D03*
X129800Y1428300D03*
X91300Y1446500D03*
X150100Y430800D03*
X145300Y568000D03*
X152800Y587000D03*
X162700Y626700D03*
X174300Y624300D03*
X148004Y1394000D03*
X140500Y1466400D03*
Y1462400D03*
X140200Y1453300D03*
X157300Y1458000D03*
G54D46*
X80709Y161889D03*
Y171889D03*
Y181889D03*
Y191889D03*
Y204409D03*
Y214409D03*
Y224409D03*
Y234409D03*
Y244409D03*
Y256929D03*
Y266929D03*
Y276929D03*
Y286929D03*
X110709Y161889D03*
Y171889D03*
X100709Y161889D03*
Y171889D03*
X90709Y161889D03*
Y171889D03*
X110709Y181889D03*
Y191889D03*
X100709Y181889D03*
Y191889D03*
X90709Y181889D03*
Y191889D03*
X110709Y204409D03*
Y214409D03*
Y224409D03*
Y234409D03*
Y244409D03*
X100709Y204409D03*
Y214409D03*
Y224409D03*
Y234409D03*
Y244409D03*
X90709Y204409D03*
Y214409D03*
Y224409D03*
Y234409D03*
Y244409D03*
X110709Y256929D03*
Y266929D03*
X100709Y256929D03*
Y266929D03*
X90709Y256929D03*
Y266929D03*
X110709Y276929D03*
Y286929D03*
X100709Y276929D03*
Y286929D03*
X90709Y276929D03*
Y286929D03*
X179606Y161889D03*
Y171889D03*
X169606Y161889D03*
Y171889D03*
X159606Y161889D03*
Y171889D03*
X149606Y161889D03*
Y171889D03*
X179606Y181889D03*
Y191889D03*
X169606Y181889D03*
Y191889D03*
X159606Y181889D03*
Y191889D03*
X149606Y181889D03*
Y191889D03*
X179606Y204409D03*
Y214409D03*
Y224409D03*
Y234409D03*
Y244409D03*
X169606Y204409D03*
Y214409D03*
Y224409D03*
Y234409D03*
Y244409D03*
X159606Y204409D03*
Y214409D03*
Y224409D03*
Y234409D03*
Y244409D03*
X149606Y204409D03*
Y214409D03*
Y224409D03*
Y234409D03*
Y244409D03*
X179606Y256929D03*
Y266929D03*
X169606Y256929D03*
Y266929D03*
X159606Y256929D03*
Y266929D03*
X149606Y256929D03*
Y266929D03*
X179606Y276929D03*
Y286929D03*
X169606Y276929D03*
Y286929D03*
X159606Y276929D03*
Y286929D03*
X149606Y276929D03*
Y286929D03*
G54D55*
X73403Y606702D03*
Y633502D03*
X122097Y1125298D03*
Y1152098D03*
X98497Y1883198D03*
Y1909998D03*
G54D92*
G01X-448201Y-66763D02*
X-480201D01*
G01X-448201Y-82763D02*
Y-162763D01*
G01Y-118263D02*
X752899D01*
G01X-448201Y-162763D02*
X752899D01*
G01X-452201Y-66763D02*
G02I-12000J0D01*
G01X-457351D02*
G02I-6850J0D01*
G01X-464201Y-82763D02*
Y-50763D01*
G01X-448201Y-82763D02*
X752899D01*
G01X-34601D02*
Y-162763D01*
G01X32750Y272300D02*
X28900D01*
X26450Y274750D01*
G01X32700Y256950D02*
X28050D01*
G01X19721Y262553D02*
Y267203D01*
G01X29050Y321300D02*
X25600D01*
X25500Y321200D01*
G01X21600Y333800D02*
Y332200D01*
X25300Y328500D01*
G01X32675Y305350D02*
Y299500D01*
G01X33450Y570800D02*
Y574300D01*
G01X39000Y577850D02*
X37000D01*
X33450Y574300D01*
G01X35000Y584850D02*
X31150D01*
X29500Y586500D01*
G01X24100Y685100D02*
X28900D01*
G01D02*
X29300D01*
X36400Y678000D01*
X48500D01*
X53000Y673500D01*
G01X31600Y1024300D02*
X33400Y1022500D01*
X39000D01*
G01X39300Y1105800D02*
X39100Y1106000D01*
X27750D01*
G01X33550Y1083600D02*
Y1080100D01*
G01X31868Y1096958D02*
X27260D01*
X27218Y1097000D01*
G01X18550Y1644300D02*
X13300D01*
G01X16200Y1657100D02*
Y1650900D01*
X14100Y1648800D01*
X10500D01*
G01X18550Y1640200D02*
X7500D01*
G01X31400Y1648200D02*
X30550Y1649050D01*
X27625D01*
G01X13300Y1689600D02*
X16500Y1692800D01*
X20150D01*
G01X15800Y1699200D02*
Y1703900D01*
X13900Y1705800D01*
Y1706200D01*
G01X19542Y1714868D02*
Y1710518D01*
G01X25900Y1721650D02*
X29000D01*
X29100Y1721550D01*
G01X34000Y1691500D02*
X32359Y1689859D01*
Y1680500D01*
G01X34150Y1774400D02*
X38200D01*
X38800Y1775000D01*
G01X34650Y1781000D02*
X37650Y1784000D01*
X41600D01*
X42000Y1784400D01*
G01X26750Y1787800D02*
X22000D01*
G01X67398Y67553D02*
X64000D01*
G01X67998Y53053D02*
X67945Y53000D01*
X64500D01*
G01X70454Y60031D02*
Y63204D01*
X70750Y63500D01*
G01X56850Y171300D02*
X53200D01*
X53000Y171500D01*
G01X60350Y155300D02*
Y151950D01*
G01Y179300D02*
X63500D01*
G01X60350Y163300D02*
X62000D01*
X65000Y166300D01*
G01X57750Y217000D02*
X54400D01*
G01X65200Y207850D02*
X61600D01*
G01X61000Y236550D02*
X62750D01*
X62800Y236500D01*
X63900D01*
X65000Y235400D01*
G01X62600Y245750D02*
Y243750D01*
X63600Y242750D01*
X63750D01*
X65000Y241500D01*
G01X61000Y236550D02*
X57424Y232974D01*
G01X42720Y233990D02*
X44910Y231800D01*
X56250D01*
X57424Y232974D01*
G01X70600Y250500D02*
Y247100D01*
X65000Y241500D01*
G01X52200Y244700D02*
X47499D01*
X47498Y244699D01*
G01D02*
Y247598D01*
X48500Y248600D01*
G01X54200Y207850D02*
X57400D01*
G01X57750Y221000D02*
X54500D01*
X54200Y220700D01*
G01X60350Y280000D02*
X62900D01*
X65675Y277225D01*
Y272675D01*
X63000Y270000D01*
Y267750D01*
G01D02*
X67750D01*
X68000Y268000D01*
G01X42500Y254100D02*
X38900Y250500D01*
Y246900D01*
G01X37200Y256950D02*
Y259186D01*
X36000Y260386D01*
G01X58936Y256289D02*
X61000Y254225D01*
Y254000D01*
X62700D01*
G01X35450Y343750D02*
X39200D01*
G01X74250Y431300D02*
X76200D01*
X78000Y429500D01*
G01X84000Y440000D02*
Y437000D01*
X81800Y434800D01*
X73300D01*
X70750Y432250D01*
Y431300D01*
G01D02*
Y427350D01*
X70900Y427200D01*
G01X72000Y491452D02*
X74148D01*
G01D02*
X82000Y483600D01*
G01X89852Y491452D02*
X82000Y483600D01*
G01X72000Y473548D02*
Y475500D01*
G01X78200Y481700D02*
X86352Y473548D01*
G01X72000Y475500D02*
X78200Y481700D01*
G01X81400Y533950D02*
X79750D01*
X77400Y536300D01*
G01X86850Y537800D02*
Y534800D01*
X85729Y533679D01*
G01X81400Y533950D02*
X85458D01*
X85729Y533679D01*
G01X86900Y549900D02*
X91400D01*
X95700Y545600D01*
X99800D01*
G01X81400Y530450D02*
X85250D01*
X87700Y528000D01*
G01X60950Y577200D02*
Y578450D01*
X63400Y580900D01*
Y581400D01*
G01X58350Y584000D02*
X60800D01*
X63400Y581400D01*
G01X58350Y593000D02*
Y584000D01*
G01X78400Y587550D02*
Y583700D01*
G01X73900Y558850D02*
X70350D01*
G01X78600Y574550D02*
Y577900D01*
X79458Y578758D01*
G01X74100Y576400D02*
X72000D01*
X69800Y574200D01*
G01X49600Y573450D02*
X54550D01*
X54600Y573400D01*
G01X60950Y573000D02*
X55000D01*
X54600Y573400D01*
G01X64000Y657600D02*
Y655700D01*
X66200Y653500D01*
G01X89435Y642629D02*
X85436D01*
X84200Y643865D01*
G01X67200Y705200D02*
X67300Y705100D01*
Y702200D01*
X62739Y697639D01*
X57684D01*
G01X78506Y690465D02*
Y689593D01*
X80650Y687449D01*
Y686400D01*
G01X65635Y688106D02*
X70535D01*
G01X57400Y676850D02*
X61400D01*
G01X78506Y690465D02*
X77617Y689576D01*
X75475D01*
X75399Y689500D01*
X71929D01*
X70535Y688106D01*
G01X57400Y676850D02*
Y680379D01*
X56710Y681069D01*
G01X65635Y688106D02*
X63100Y685571D01*
Y680200D01*
X61400Y678500D01*
Y676850D01*
G01X80650Y686400D02*
X79050Y684800D01*
X78278D01*
X78078Y684600D01*
X77600D01*
X76000Y683000D01*
Y679700D01*
X88000Y667700D01*
X93250D01*
X95200Y665750D01*
G01X72200Y705200D02*
X67200D01*
G01X70535Y694106D02*
Y695065D01*
X69100Y696500D01*
Y698006D01*
G01X64000Y662300D02*
Y666600D01*
G01X78494Y694635D02*
Y697835D01*
G01X69000Y726800D02*
Y727000D01*
X68750Y727250D01*
Y730000D01*
G01X71500Y735500D02*
X72500D01*
X74950Y737950D01*
X75200D01*
G01X77000Y730850D02*
X74650D01*
X73500Y732000D01*
G01X57500Y844500D02*
X57900Y844100D01*
X83946D01*
G01D02*
Y848500D01*
G01D02*
Y852900D01*
G01X83950Y857200D02*
Y852904D01*
X83946Y852900D01*
G01X83950Y861500D02*
Y857200D01*
G01Y865700D02*
Y861500D01*
G01Y865700D02*
Y869104D01*
X87500Y872654D01*
G01X43400Y892650D02*
X46650Y889400D01*
X49600D01*
G01X49900Y883800D02*
X51900D01*
X55700Y880000D01*
G01X54300Y915500D02*
Y913400D01*
X50942Y910042D01*
Y909868D01*
G01X48850Y916400D02*
X53400D01*
X54300Y915500D01*
G01X64000Y980500D02*
X63950Y980450D01*
X57100D01*
G01X75850Y1020900D02*
Y1014200D01*
X73450Y1011800D01*
G01X72150Y1004300D02*
Y1010500D01*
X73450Y1011800D01*
G01X63800Y986600D02*
X62600D01*
X60300Y984300D01*
X57500D01*
G01X88000Y976300D02*
X83500D01*
G01X53800Y1009550D02*
Y1006200D01*
G01X70800Y975600D02*
X63800D01*
G01X70800D02*
X71500Y976300D01*
X77400D01*
G01X75750Y1025400D02*
Y1021000D01*
X75850Y1020900D01*
G01X75750Y1025400D02*
Y1030100D01*
X77750Y1032100D01*
G01X59550Y1020600D02*
X56900D01*
X56000Y1021500D01*
G01X58100Y1034350D02*
X55650D01*
X54500Y1035500D01*
G01X63700Y1090600D02*
Y1098200D01*
X64500Y1099000D01*
G01X83450Y1143000D02*
X80156D01*
X79044Y1144112D01*
G01X67650Y1144500D02*
Y1147850D01*
X66000Y1149500D01*
G01D02*
X63198Y1146698D01*
Y1142053D01*
G01X77002Y1134447D02*
X76447D01*
X74000Y1132000D01*
G01X72250Y1175100D02*
Y1172150D01*
X71100Y1171000D01*
G01X80000Y1472000D02*
X80200Y1472200D01*
Y1477500D01*
G01X83500Y1465250D02*
Y1469500D01*
G01X85000Y1490000D02*
X84250Y1489250D01*
Y1484000D01*
G01X107500Y1490250D02*
X105949Y1491801D01*
X86801D01*
X85000Y1490000D01*
G01X67700Y1568700D02*
X72200D01*
X75400Y1571900D01*
Y1575600D01*
G01X48400Y1746900D02*
Y1752150D01*
X48300Y1752250D01*
G01X41600Y1754250D02*
Y1746900D01*
G01X42000Y1784400D02*
X38450Y1787950D01*
Y1788200D01*
G01X102899Y-82763D02*
Y-162763D01*
G01X122500Y441000D02*
X121350Y439850D01*
Y437500D01*
G01X111500Y439500D02*
X113500Y437500D01*
X117850D01*
G01X118500Y442000D02*
X117850Y441350D01*
Y437500D01*
G01X90000Y491452D02*
X89852D01*
G01X108100Y477650D02*
X105150D01*
X103900Y476400D01*
G01X86352Y473548D02*
X90000D01*
G01X96100Y530450D02*
X93550D01*
X91300Y528200D01*
G01X106300Y553200D02*
X106200Y553300D01*
X102150D01*
G01X90350Y537800D02*
Y535058D01*
X91729Y533679D01*
G01X96100Y533950D02*
X92000D01*
X91729Y533679D01*
G01X96150Y537800D02*
Y534000D01*
X96100Y533950D01*
G01X96900Y541600D02*
X96150Y540850D01*
Y537800D01*
G01X102150Y549600D02*
X109200D01*
X110400Y550800D01*
G01X99800Y545600D02*
X100100D01*
X102150Y547650D01*
Y549600D01*
G01X98650Y553300D02*
Y549600D01*
G01X136779Y539621D02*
X132500D01*
G01X158535Y603879D02*
Y596035D01*
X154300Y591800D01*
X146600D01*
X136600Y581800D01*
Y574198D01*
X126393Y563991D01*
X105521D01*
X97500Y572012D01*
Y581700D01*
X93065Y586135D01*
Y594021D01*
G01X103500Y593950D02*
Y588000D01*
X103100Y587600D01*
G01X87400Y577650D02*
Y581005D01*
X87595Y581200D01*
Y581300D01*
G01X124900Y585154D02*
Y582000D01*
G01X120800Y585154D02*
Y581700D01*
X121000Y581500D01*
G01X91300Y573250D02*
Y577000D01*
G01X96300Y557500D02*
X95900D01*
X92200Y553800D01*
G01X101800Y557400D02*
X101700D01*
X98650Y554350D01*
Y553300D01*
G01X128900Y585146D02*
Y580500D01*
G01X122300Y575000D02*
X119897D01*
X116800Y578097D01*
Y585146D01*
G01X129065Y678894D02*
X123465D01*
G01D02*
X121986Y677415D01*
X113306D01*
G01D02*
Y675706D01*
X108700Y671100D01*
X106700D01*
X103300Y667700D01*
X97150D01*
X95200Y665750D01*
G01X129065Y678894D02*
X136454D01*
X145548Y669800D01*
G01X91250Y707900D02*
Y704700D01*
G01X134600Y665600D02*
X133535Y664535D01*
Y662079D01*
G01X129065Y672894D02*
X132494D01*
X134100Y674500D01*
G01X123465Y672894D02*
X119406D01*
X119000Y673300D01*
G01X117291Y710500D02*
Y706791D01*
X115000Y704500D01*
G01X103256Y684915D02*
Y690611D01*
X99001Y694866D01*
G01X129306Y683665D02*
Y688065D01*
G01D02*
Y691565D01*
X129406Y691665D01*
Y692165D01*
G01X129800Y696800D02*
X129406Y696406D01*
G01D02*
Y692165D01*
G01X158600Y752600D02*
X151822D01*
X135400Y736178D01*
Y730050D01*
G01X124900Y728400D02*
X133750D01*
X135400Y730050D01*
G01X116000Y764100D02*
X117200D01*
X121000Y767900D01*
G01X116000Y769100D02*
X119800D01*
X121000Y767900D01*
G01X92300Y872654D02*
X87500D01*
G01X121671Y936306D02*
X127500D01*
X131306Y932500D01*
X141300D01*
X145000Y936200D01*
Y945750D01*
G01X112529Y952294D02*
Y952029D01*
X110000Y949500D01*
G01X117529Y952294D02*
Y948844D01*
G01X93000Y925500D02*
X96000Y928500D01*
Y931000D01*
G01X168000Y977500D02*
X162002Y971502D01*
X128998D01*
X126500Y974000D01*
Y977546D01*
X125046Y979000D01*
G01X107300Y990800D02*
X112000D01*
G01X107300Y986000D02*
Y990800D01*
G01X130800Y981600D02*
X128200Y979000D01*
X125046D01*
G01D02*
X124710Y979336D01*
X112364D01*
X107300Y984400D01*
Y986000D01*
G01X101300Y990800D02*
X97300D01*
G01X101300Y986000D02*
Y990800D01*
G01X94500Y976500D02*
X88200D01*
X88000Y976300D01*
G01X114800Y1001350D02*
Y1005000D01*
G01X104000Y1062500D02*
X105500Y1061000D01*
Y1058400D01*
G01X104000Y1049500D02*
X105500Y1051000D01*
Y1053700D01*
G01X110000Y1418000D02*
X109650Y1418350D01*
Y1421600D01*
G01X128875Y1401954D02*
X125646D01*
X125100Y1402500D01*
G01X125000Y1398500D02*
X125500Y1398000D01*
X132146D01*
X134700Y1400554D01*
G01X124696Y1392300D02*
Y1398196D01*
X125000Y1398500D01*
G01X133500Y1471000D02*
Y1467100D01*
G01X129750Y1432000D02*
Y1428300D01*
G01X132200Y1424800D02*
Y1424978D01*
X129750Y1427428D01*
Y1428300D01*
G01X91250Y1446500D02*
X87700D01*
G01X95500Y1468000D02*
Y1464250D01*
G01X89500Y1469300D02*
X94200D01*
X95500Y1468000D01*
G01X101000Y1474500D02*
Y1473000D01*
X103700Y1470300D01*
G01X94000Y1427800D02*
X95600Y1426200D01*
Y1423750D01*
G01X87200Y1431900D02*
X87600Y1431500D01*
X91250D01*
G01X136100Y1463900D02*
Y1461300D01*
X131900Y1457100D01*
G01X140450Y1466400D02*
X138600D01*
X136100Y1463900D01*
G01X91250Y1439000D02*
X88200D01*
X87200Y1440000D01*
G01X95000Y1455500D02*
X97400D01*
X97500Y1455600D01*
X99800D01*
G01X94750Y1451000D02*
X95000Y1451250D01*
Y1455500D01*
G01X89000Y1428171D02*
Y1426250D01*
X91500Y1423750D01*
G01X94750Y1439000D02*
Y1442800D01*
G01Y1446500D02*
X95100D01*
X96537Y1447937D01*
X96637D01*
X99400Y1450700D01*
X99700D01*
G01X94750Y1442800D02*
Y1446500D01*
G01X129000Y1473750D02*
Y1470500D01*
X127300Y1468800D01*
G01D02*
X124400Y1465900D01*
G01X93500Y1479250D02*
Y1482700D01*
G01X99170Y1480640D02*
Y1485790D01*
G01X112750Y1491250D02*
X108500D01*
X107500Y1490250D01*
G01X137800Y1487750D02*
X137900Y1487650D01*
G01X129000Y1477250D02*
Y1481750D01*
X128750Y1482000D01*
G01X130180Y1486680D02*
X128750Y1485250D01*
Y1482000D01*
G01X137800Y1487750D02*
X131250D01*
X130180Y1486680D01*
G01X132250Y1482000D02*
X135925D01*
X136500Y1481425D01*
G01D02*
Y1480000D01*
X133500Y1477000D01*
G01X132300Y1491100D02*
X137850D01*
X137900Y1491150D01*
G01X108500Y1575500D02*
Y1569000D01*
G01X156000Y439500D02*
Y433250D01*
X153550Y430800D01*
G01X156000Y439500D02*
X161281D01*
X162612Y438169D01*
G01X150050Y430800D02*
X148560D01*
X146960Y432400D01*
G01X184000Y439500D02*
X190750D01*
G01X176000Y490952D02*
Y489600D01*
G01X158000Y490952D02*
X160448D01*
Y490852D01*
G01X176000Y489600D02*
X169200Y482800D01*
G01X160448Y490852D02*
X168500Y482800D01*
X169200D01*
G01X146700Y476500D02*
X144000D01*
X142000Y478500D01*
G01X158000Y473048D02*
Y473800D01*
G01X165300Y481100D02*
Y481000D01*
X173252Y473048D01*
G01X158000Y473800D02*
X165300Y481100D01*
G01X173252Y473048D02*
X176000D01*
G01X166100Y527900D02*
X169450D01*
X170600Y529050D01*
G01X159850Y549300D02*
Y553250D01*
X159900Y553300D01*
G01D02*
X157500D01*
X156300Y552100D01*
G01X164450Y536500D02*
Y533750D01*
X166100Y532100D01*
G01X170600Y532550D02*
X166550D01*
X166100Y532100D01*
G01X170650Y536400D02*
Y532600D01*
G01D02*
X174400D01*
X174800Y532200D01*
G01X170650Y532600D02*
X170600Y532550D01*
G01X160950Y536500D02*
Y532950D01*
X160100Y532100D01*
G01X155600Y532450D02*
X159750D01*
X160100Y532100D01*
G01X155600Y532450D02*
X152050D01*
X151500Y533000D01*
G01X163350Y545600D02*
Y549300D01*
G01X164200Y541900D02*
Y544750D01*
X163350Y545600D01*
G01X162500Y527900D02*
X156650D01*
X155600Y528950D01*
G01X159850Y541800D02*
Y545600D01*
G01D02*
X157800D01*
X155392Y548008D01*
X151072D01*
G01X182221Y613535D02*
Y610118D01*
X173903Y601800D01*
X160614D01*
X158535Y603879D01*
G01X158000Y578650D02*
X157450D01*
X154600Y581500D01*
G01X159250Y590250D02*
Y590000D01*
X156250Y587000D01*
G01X140400Y572400D02*
Y572600D01*
G01X146365Y607771D02*
Y604865D01*
X145500Y604000D01*
G01X150500Y596000D02*
X152265Y597765D01*
Y601371D01*
G01X153500Y570050D02*
Y574359D01*
G01X142100Y581400D02*
X142950Y582250D01*
X145300D01*
G01X140400Y572600D02*
Y576300D01*
X140700Y576600D01*
G01X180465Y634971D02*
X171522D01*
X171370Y634819D01*
G01X180465Y634971D02*
X182029D01*
X183700Y633300D01*
Y615014D01*
X182221Y613535D01*
G01X180465Y634971D02*
Y642221D01*
X180365Y642321D01*
G01D02*
X181621D01*
X183194Y643894D01*
Y649006D01*
X162400Y669800D01*
X145548D01*
G01X165600Y630269D02*
X164765D01*
X162750Y628254D01*
Y626800D01*
X162650Y626700D01*
G01X164600Y612050D02*
Y615350D01*
X164950Y615700D01*
G01X180465Y631371D02*
Y628535D01*
X180500Y628500D01*
Y627771D01*
G01X175800Y617635D02*
X172535D01*
X170100Y615200D01*
G01X159700Y652000D02*
X159800Y651900D01*
Y645839D01*
G01X177750Y624300D02*
Y625238D01*
X174792Y628196D01*
X174196D01*
G01X145548Y669800D02*
Y664227D01*
X145409Y664088D01*
Y663907D01*
X143623Y662121D01*
X137765D01*
G01X165433Y692372D02*
X163300Y694505D01*
Y696300D01*
G01X150500Y702750D02*
X147250D01*
X147000Y703000D01*
G01X149375Y682250D02*
Y677375D01*
X149000Y677000D01*
G01X147000Y732000D02*
Y737000D01*
X146000Y738000D01*
G01X157000Y945750D02*
X162750D01*
X168000Y951000D01*
Y977500D01*
G01X149000Y945750D02*
X145000D01*
G01X157000D02*
X153000D01*
G01X149000D02*
X153000D01*
G01X168000Y977500D02*
Y995000D01*
X165250Y997750D01*
X163500D01*
G01D02*
X159500D01*
G01X152100Y1003250D02*
X154000D01*
X159500Y997750D01*
G01X147900Y1003150D02*
X152000D01*
X152100Y1003250D01*
G01X143800D02*
X147800D01*
X147900Y1003150D01*
G01X154600Y1111000D02*
X154453Y1111147D01*
X149002D01*
G01X146500Y1417619D02*
Y1422213D01*
X146444Y1422269D01*
G01X146500Y1397100D02*
Y1396954D01*
X147954Y1395500D01*
Y1394000D01*
G01X155775Y1401454D02*
Y1397225D01*
X155900Y1397100D01*
G01X154000Y1387500D02*
X153000D01*
X148000Y1392500D01*
Y1393954D01*
X147954Y1394000D01*
G01X139900Y1415100D02*
X140900Y1414100D01*
X151146D01*
X152046Y1415000D01*
G01Y1419200D02*
Y1423396D01*
X152050Y1423400D01*
G01X152046Y1419200D02*
Y1415000D01*
G01X143950Y1458400D02*
X147900D01*
X149507Y1460007D01*
X149686D01*
G01X154500Y1462500D02*
X151500Y1459500D01*
X150193D01*
X149686Y1460007D01*
G01X173244Y1437469D02*
X173375Y1437338D01*
Y1432500D01*
G01X165400Y1426750D02*
X169000D01*
G01X167000Y1465300D02*
X165800Y1466500D01*
X158500D01*
G01X152050Y1423400D02*
Y1427350D01*
X152331Y1427631D01*
G01X152500Y1456000D02*
X151000Y1454500D01*
X148000D01*
X146800Y1453300D01*
X143650D01*
G01X148500Y1474150D02*
X144650D01*
X142300Y1471800D01*
G01X142000Y1491250D02*
Y1494800D01*
G01X146500Y1491250D02*
Y1497000D01*
X147500Y1498000D01*
G01X151000Y1491250D02*
Y1494000D01*
X153500Y1496500D01*
G01X142300Y1480800D02*
Y1487450D01*
X142000Y1487750D01*
G01X146500D02*
X142000D01*
G01X151000D02*
X146500D01*
G01X142000D02*
X137800D01*
G01X148500Y1479500D02*
Y1474150D01*
G01X143500Y1575500D02*
Y1567538D01*
X143518Y1567520D01*
G01X177500Y1575500D02*
Y1569500D01*
G01X217899Y-82763D02*
Y-162763D01*
G01X191400Y432405D02*
Y432500D01*
X194250Y435350D01*
Y439500D01*
G01X189928Y435800D02*
X190750Y436622D01*
Y439500D01*
G01X385399Y-82763D02*
Y-162763D01*
G01X555399Y-82763D02*
Y-162763D01*
G01X752899Y-82763D02*
Y-162763D01*
G01X780899Y-66763D02*
G02I-12000J0D01*
G01X775749D02*
G02I-6850J0D01*
G01X768899Y-82763D02*
Y-50763D01*
G01X784899Y-66763D02*
X752899D01*
G54D38*
X26700Y1787800D03*
X60900Y573000D03*
X78300Y966200D03*
X83400Y1143000D03*
X67600Y1144500D03*
X91200Y1431500D03*
Y1434900D03*
X129700Y1432000D03*
X91200Y1442800D03*
X159800Y549300D03*
X140700Y695500D03*
G54D83*
X117000Y1452000D03*
G54D65*
X78900Y1498700D03*
Y1523500D03*
X124298Y1883503D03*
Y1908303D03*
X145798Y1151303D03*
Y1126503D03*
G54D56*
X56000Y623450D03*
Y615550D03*
X80100Y1891950D03*
Y1899850D03*
X105100Y1135550D03*
Y1143450D03*
G54D29*
X36250Y690560D03*
Y688000D03*
Y685440D03*
X51750Y690560D03*
Y688000D03*
Y685440D03*
X58250D03*
Y690560D03*
X42750Y685440D03*
Y690560D03*
G54D74*
X103256Y684915D03*
G54D47*
X47498Y238899D03*
X52200Y238900D03*
X62700Y254200D03*
X45100Y577300D03*
X81500Y727600D03*
X63202Y1128347D03*
X103900Y476600D03*
X96300Y557700D03*
X129065Y673094D03*
X123465D03*
X124900Y722600D03*
X94500Y976700D03*
X130800Y975800D03*
X133500Y1471200D03*
X146700Y476700D03*
X163300Y696500D03*
X144300Y1111300D03*
X149002Y1111347D03*
G54D93*
G01X85400Y544750D02*
Y548400D01*
X86900Y549900D01*
G01X73700Y539850D02*
X74150Y540300D01*
X77800D01*
G01X83430Y544750D02*
Y541080D01*
X82650Y540300D01*
X77800D01*
G01X81465Y561050D02*
Y563935D01*
X79700Y565700D01*
X79122D01*
G01X66875Y681106D02*
Y686866D01*
X65635Y688106D01*
G01X136779Y539621D02*
X138600Y537800D01*
X146030D01*
X147230Y539000D01*
Y542950D01*
G01X130800Y981600D02*
X137240D01*
X137340Y981700D01*
G01X153135Y542950D02*
Y539665D01*
X153900Y538900D01*
X163100D01*
X164450Y537550D01*
Y536500D01*
G01X160950D02*
X152600D01*
X151170Y537930D01*
Y542950D01*
G01X151072Y548008D02*
X149200Y546136D01*
Y542950D01*
G01X171175Y710104D02*
X174996D01*
X175100Y710000D01*
G54D57*
X66875Y674606D03*
X69435D03*
X71995D03*
Y681106D03*
X66875D03*
G54D66*
X71250Y1613297D03*
Y1619703D03*
X130250Y1613297D03*
Y1619703D03*
X101750Y1613297D03*
Y1619703D03*
X157750Y1613297D03*
Y1619703D03*
G54D75*
X134709Y710500D03*
X117291D03*
G54D48*
X47498Y244499D03*
X52200Y244500D03*
X62700Y259800D03*
X45100Y582900D03*
X81500Y733200D03*
X63202Y1133947D03*
X103900Y482200D03*
X96300Y563300D03*
X129065Y678694D03*
X123465D03*
X124900Y728200D03*
X94500Y982300D03*
X130800Y981400D03*
X133500Y1476800D03*
X146700Y482300D03*
X163300Y702100D03*
X144300Y1116900D03*
X149002Y1116947D03*
G54D84*
X129000Y1474150D03*
G54D39*
X72200Y86200D03*
X72602Y757897D03*
X63700Y1050100D03*
X99000Y86200D03*
X99402Y757897D03*
X90500Y1050100D03*
G54D94*
G01X104500Y932700D02*
Y924000D01*
X101800Y921300D01*
X87700D01*
X80400Y928600D01*
Y928616D01*
X78116Y930900D01*
X78100D01*
X77101Y931899D01*
X41000D01*
G01X57100Y974450D02*
X56750Y974100D01*
G01D02*
X51500D01*
G01X64500Y1165700D02*
X87300D01*
X89000Y1167400D01*
G54D67*
X96457Y1773425D03*
G54D58*
X49900Y883800D03*
Y894800D03*
X63800Y986600D03*
Y975600D03*
X39000Y1022500D03*
Y1033500D03*
X96000Y931000D03*
Y942000D03*
X147000Y732000D03*
Y721000D03*
G54D76*
X116175Y846304D03*
X113620D03*
X111060D03*
X108500D03*
X105940D03*
X103380D03*
X100825D03*
Y868504D03*
X103380D03*
X105940D03*
X108500D03*
X111060D03*
X113620D03*
X116175D03*
X121640Y963000D03*
X119080D03*
X116520D03*
X113960D03*
Y985200D03*
X116520D03*
X119080D03*
X121640D03*
X155825Y732304D03*
X158380D03*
X160940D03*
X163500D03*
X166060D03*
X168620D03*
X171175D03*
Y710104D03*
X168620D03*
X166060D03*
X163500D03*
X160940D03*
X158380D03*
X155825D03*
X137340Y959500D03*
X139900D03*
X142460D03*
X145020D03*
X147580D03*
X150140D03*
X152700D03*
X155260D03*
Y981700D03*
X152700D03*
X150140D03*
X147580D03*
X145020D03*
X142460D03*
X139900D03*
X137340D03*
G54D85*
X129000Y1476850D03*
G54D49*
X69635Y361900D03*
X110735Y361800D03*
X140465D03*
X99365Y361900D03*
X187565Y1507700D03*
X157835D03*
G54D95*
G01X92300Y872654D02*
X96450Y868504D01*
X100825D01*
G01X112000Y990800D02*
X113960Y988840D01*
Y985200D01*
G54D59*
X86699Y949600D03*
X63901D03*
G54D77*
X104500Y933512D03*
G54D68*
X48200Y1760300D03*
X98600Y553300D03*
X86800Y537800D03*
X96100D03*
X112900Y603500D03*
X107600Y593700D03*
X170600Y536400D03*
X160900Y536500D03*
G54D86*
X161417Y1773425D03*
G54D96*
G01X131900Y1457100D02*
Y1456100D01*
X130359Y1454559D01*
X126600D01*
G01X99800Y1455600D02*
X100841Y1454559D01*
X107400D01*
G01X140450Y1458400D02*
X138100D01*
X134400Y1454700D01*
Y1454300D01*
G01X126600Y1452000D02*
X132200D01*
X134400Y1454200D01*
Y1454300D01*
G01X99700Y1450700D02*
X101000Y1452000D01*
X107400D01*
G01X124400Y1465900D02*
X122118Y1463618D01*
Y1461600D01*
G01X140450Y1462400D02*
Y1458400D01*
G54D78*
X104500Y939475D03*
G54D87*
X171370Y634819D03*
X159800D03*
X171370Y645839D03*
X159800D03*
G54D69*
X51800Y1760300D03*
X102200Y553300D03*
X90400Y537800D03*
X99700D03*
X116500Y603500D03*
X111200Y593700D03*
X174200Y536400D03*
X164500Y536500D03*
G54D97*
G01X57684Y697639D02*
X55323Y700000D01*
X43000D01*
X39131Y696131D01*
Y693869D01*
X42440Y690560D01*
X42750D01*
G01X58250D02*
Y697073D01*
X57684Y697639D01*
G01X106400Y1402260D02*
X100860D01*
G01X113800Y1397140D02*
Y1396800D01*
X111000Y1394000D01*
G01X126600Y1457118D02*
Y1461500D01*
G54D79*
X113800Y1397140D03*
Y1399700D03*
Y1402260D03*
X106400D03*
Y1399700D03*
Y1397140D03*
G54D88*
X180465Y631371D03*
Y634971D03*
G54D98*
G01X15906Y73908D02*
Y78110D01*
G01D02*
Y82312D01*
G01X11704Y78110D02*
X15906D01*
G01D02*
X20108D01*
G01X15906Y88110D02*
Y92312D01*
G01X11704Y88110D02*
X15906D01*
G01D02*
X20108D01*
G01X27559Y140328D02*
Y157480D01*
G01D02*
Y174632D01*
G01X10407Y157480D02*
X27559D01*
G01D02*
X44711D01*
G01X15906Y511339D02*
Y515541D01*
G01X11704Y511339D02*
X15906D01*
G01D02*
X20108D01*
G01X27559Y612769D02*
Y629921D01*
G01D02*
Y647073D01*
G01X10407Y629921D02*
X27559D01*
G01X15906Y766979D02*
Y771181D01*
G01D02*
Y775383D01*
G01X11704Y771181D02*
X15906D01*
G01D02*
X20108D01*
G01X15906Y781181D02*
X20108D01*
G01X15906D02*
X19077Y784352D01*
G01X15906Y1213121D02*
Y1217323D01*
G01D02*
Y1221525D01*
G01X11704Y1217323D02*
X15906D01*
G01D02*
X20108D01*
G01X15906Y1227323D02*
Y1231525D01*
G01X11704Y1227323D02*
X15906D01*
G01D02*
X20108D01*
G01X17716Y1321431D02*
Y1338583D01*
G01D02*
Y1355735D01*
G01Y1338583D02*
X34868D01*
G01X15906Y1472963D02*
Y1477165D01*
G01D02*
Y1481367D01*
G01X11704Y1477165D02*
X15906D01*
G01D02*
X20108D01*
G01X15906Y1487165D02*
Y1491367D01*
G01X11704Y1487165D02*
X15906D01*
G01D02*
X20108D01*
G01X27559Y1793871D02*
Y1811023D01*
G01D02*
Y1828175D01*
G01X10407Y1811023D02*
X27559D01*
G01D02*
X44711D01*
G01X15906Y1906192D02*
Y1910394D01*
G01D02*
Y1914596D01*
G01X11704Y1910394D02*
X15906D01*
G01D02*
X20108D01*
G01X15906Y1920394D02*
Y1924596D01*
G01X11704Y1920394D02*
X15906D01*
G01D02*
X20108D01*
G01X86457Y286929D02*
X90709D01*
G01X86457Y276929D02*
X90709D01*
G01X86457Y266929D02*
X90709D01*
G01X86457Y256929D02*
X90709D01*
G01X80709Y282677D02*
Y286929D01*
G01D02*
Y291181D01*
G01X76457Y286929D02*
X80709D01*
G01D02*
X84961D01*
G01X80709Y272677D02*
Y276929D01*
G01D02*
Y281181D01*
G01X76457Y276929D02*
X80709D01*
G01D02*
X84961D01*
G01X80709Y262677D02*
Y266929D01*
G01D02*
Y271181D01*
G01X76457Y266929D02*
X80709D01*
G01D02*
X84961D01*
G01X80709Y256929D02*
Y261181D01*
G01X76457Y256929D02*
X80709D01*
G01D02*
X84961D01*
G01X76305Y1747835D02*
X96457D01*
G01X76305Y1823031D02*
X96457D01*
G01X90709Y282677D02*
Y286929D01*
G01D02*
Y291181D01*
G01Y286929D02*
X94961D01*
G01X90709Y272677D02*
Y276929D01*
G01D02*
Y281181D01*
G01Y276929D02*
X94961D01*
G01X100709Y282677D02*
Y286929D01*
G01D02*
Y291181D01*
G01X96457Y286929D02*
X100709D01*
G01D02*
X104961D01*
G01X100709Y272677D02*
Y276929D01*
G01D02*
Y281181D01*
G01X96457Y276929D02*
X100709D01*
G01D02*
X104961D01*
G01X110709Y282677D02*
Y286929D01*
G01D02*
Y291181D01*
G01X106457Y286929D02*
X110709D01*
G01D02*
X114961D01*
G01X110709Y272677D02*
Y276929D01*
G01D02*
Y281181D01*
G01X106457Y276929D02*
X110709D01*
G01D02*
X114961D01*
G01X90709Y262677D02*
Y266929D01*
G01D02*
Y271181D01*
G01Y266929D02*
X94961D01*
G01X90709Y256929D02*
Y261181D01*
G01Y256929D02*
X94961D01*
G01X100709Y262677D02*
Y266929D01*
G01D02*
Y271181D01*
G01X96457Y266929D02*
X100709D01*
G01D02*
X104961D01*
G01X100709Y256929D02*
Y261181D01*
G01X96457Y256929D02*
X100709D01*
G01D02*
X104961D01*
G01X110709Y262677D02*
Y266929D01*
G01D02*
Y271181D01*
G01X106457Y266929D02*
X110709D01*
G01D02*
X114961D01*
G01X110709Y256929D02*
Y261181D01*
G01X106457Y256929D02*
X110709D01*
G01X96457Y1727683D02*
Y1747835D01*
G01D02*
Y1767987D01*
G01Y1747835D02*
X116609D01*
G01X96457Y1802879D02*
Y1823031D01*
G01D02*
Y1843183D01*
G01Y1823031D02*
X116609D01*
G01X179134Y61588D02*
Y78740D01*
G01D02*
Y95892D01*
G01X161982Y78740D02*
X179134D01*
G01D02*
X196286D01*
G01X149606Y187637D02*
Y191889D01*
G01D02*
Y196141D01*
G01X145354Y191889D02*
X149606D01*
G01D02*
X153858D01*
G01X149606Y177637D02*
Y181889D01*
G01D02*
Y186141D01*
G01X145354Y181889D02*
X149606D01*
G01D02*
X153858D01*
G01X159606Y187637D02*
Y191889D01*
G01D02*
Y196141D01*
G01X155354Y191889D02*
X159606D01*
G01D02*
X163858D01*
G01X159606Y177637D02*
Y181889D01*
G01D02*
Y186141D01*
G01X155354Y181889D02*
X159606D01*
G01D02*
X163858D01*
G01X169606Y187637D02*
Y191889D01*
G01D02*
Y196141D01*
G01X165354Y191889D02*
X169606D01*
G01D02*
X173858D01*
G01X169606Y177637D02*
Y181889D01*
G01D02*
Y186141D01*
G01X165354Y181889D02*
X169606D01*
G01D02*
X173858D01*
G01X179606Y187637D02*
Y191889D01*
G01D02*
Y196141D01*
G01X175354Y191889D02*
X179606D01*
G01D02*
X183858D01*
G01X179606Y177637D02*
Y181889D01*
G01D02*
Y186141D01*
G01X175354Y181889D02*
X179606D01*
G01D02*
X183858D01*
G01X149606Y167637D02*
Y171889D01*
G01D02*
Y176141D01*
G01X145354Y171889D02*
X149606D01*
G01D02*
X153858D01*
G01X149606Y157637D02*
Y161889D01*
G01D02*
Y166141D01*
G01X145354Y161889D02*
X149606D01*
G01D02*
X153858D01*
G01X159606Y167637D02*
Y171889D01*
G01D02*
Y176141D01*
G01X155354Y171889D02*
X159606D01*
G01D02*
X163858D01*
G01X159606Y157637D02*
Y161889D01*
G01D02*
Y166141D01*
G01X155354Y161889D02*
X159606D01*
G01D02*
X163858D01*
G01X169606Y167637D02*
Y171889D01*
G01D02*
Y176141D01*
G01X165354Y171889D02*
X169606D01*
G01D02*
X173858D01*
G01X169606Y157637D02*
Y161889D01*
G01D02*
Y166141D01*
G01X165354Y161889D02*
X169606D01*
G01D02*
X173858D01*
G01X179606Y167637D02*
Y171889D01*
G01D02*
Y176141D01*
G01X175354Y171889D02*
X179606D01*
G01D02*
X183858D01*
G01X179606Y157637D02*
Y161889D01*
G01D02*
Y166141D01*
G01X175354Y161889D02*
X179606D01*
G01D02*
X183858D01*
G01X149606Y282677D02*
Y286929D01*
G01D02*
Y291181D01*
G01X145354Y286929D02*
X149606D01*
G01D02*
X153858D01*
G01X149606Y272677D02*
Y276929D01*
G01D02*
Y281181D01*
G01X145354Y276929D02*
X149606D01*
G01D02*
X153858D01*
G01X159606Y282677D02*
Y286929D01*
G01D02*
Y291181D01*
G01X155354Y286929D02*
X159606D01*
G01D02*
X163858D01*
G01X159606Y272677D02*
Y276929D01*
G01D02*
Y281181D01*
G01X155354Y276929D02*
X159606D01*
G01D02*
X163858D01*
G01X169606Y282677D02*
Y286929D01*
G01D02*
Y291181D01*
G01X165354Y286929D02*
X169606D01*
G01D02*
X173858D01*
G01X169606Y272677D02*
Y276929D01*
G01D02*
Y281181D01*
G01X165354Y276929D02*
X169606D01*
G01D02*
X173858D01*
G01X179606Y282677D02*
Y286929D01*
G01D02*
Y291181D01*
G01X175354Y286929D02*
X179606D01*
G01D02*
X183858D01*
G01X179606Y272677D02*
Y276929D01*
G01D02*
Y281181D01*
G01X175354Y276929D02*
X179606D01*
G01D02*
X183858D01*
G01X149606Y262677D02*
Y266929D01*
G01D02*
Y271181D01*
G01X145354Y266929D02*
X149606D01*
G01D02*
X153858D01*
G01X149606Y252677D02*
Y256929D01*
G01D02*
Y261181D01*
G01X145354Y256929D02*
X149606D01*
G01D02*
X153858D01*
G01X159606Y262677D02*
Y266929D01*
G01D02*
Y271181D01*
G01X155354Y266929D02*
X159606D01*
G01D02*
X163858D01*
G01X159606Y252677D02*
Y256929D01*
G01D02*
Y261181D01*
G01X155354Y256929D02*
X159606D01*
G01D02*
X163858D01*
G01X169606Y262677D02*
Y266929D01*
G01D02*
Y271181D01*
G01X165354Y266929D02*
X169606D01*
G01D02*
X173858D01*
G01X169606Y252677D02*
Y256929D01*
G01D02*
Y261181D01*
G01X165354Y256929D02*
X169606D01*
G01D02*
X173858D01*
G01X179606Y262677D02*
Y266929D01*
G01D02*
Y271181D01*
G01X175354Y266929D02*
X179606D01*
G01D02*
X183858D01*
G01X179606Y252677D02*
Y256929D01*
G01D02*
Y261181D01*
G01X175354Y256929D02*
X179606D01*
G01D02*
X183858D01*
G01X179133Y553714D02*
Y570866D01*
G01D02*
Y588018D01*
G01X161981Y570866D02*
X179133D01*
G01D02*
X196285D01*
G01X179134Y1144265D02*
Y1161417D01*
G01D02*
Y1178569D01*
G01X161982Y1161417D02*
X179134D01*
G01D02*
X196286D01*
G01X178937Y1308588D02*
Y1328740D01*
G01D02*
Y1348892D01*
G01X158785Y1328740D02*
X178937D01*
G01D02*
X199089D01*
G01X161417Y1727683D02*
Y1747835D01*
G01D02*
Y1767987D01*
G01X141265Y1747835D02*
X161417D01*
G01D02*
X181569D01*
G01X161417Y1802879D02*
Y1823031D01*
G01D02*
Y1843183D01*
G01X141265Y1823031D02*
X161417D01*
G01D02*
X181569D01*
G01X179134Y1872612D02*
Y1889764D01*
G01D02*
Y1906916D01*
G01X161982Y1889764D02*
X179134D01*
G01D02*
X196286D01*
G54D89*
X141100Y1401696D03*
Y1410096D03*
X158600Y1446404D03*
Y1438004D03*
G54D99*
G01X121640Y963000D02*
Y960960D01*
X123356Y959244D01*
X124618D01*
M02*
